G04 ================== begin FILE IDENTIFICATION RECORD ==================*
G04 Layout Name:  15105-sa.brd*
G04 Film Name:    L7GND*
G04 File Format:  Gerber RS274X*
G04 File Origin:  Cadence Allegro 16.5-S056*
G04 Origin Date:  Wed Nov 16 02:02:26 2016*
G04 *
G04 Layer:  VIA CLASS/L7GND*
G04 Layer:  PIN/L7GND*
G04 Layer:  ETCH/L7GND*
G04 Layer:  DRAWING FORMAT/LAYER_PCB_STORY*
G04 Layer:  DRAWING FORMAT/LAYER_L7GND*
G04 *
G04 Offset:    (0.00 0.00)*
G04 Mirror:    No*
G04 Mode:      Negative*
G04 Rotation:  0*
G04 FullContactRelief:  No*
G04 UndefLineWidth:     6.00*
G04 ================== end FILE IDENTIFICATION RECORD ====================*
%FSLAX35Y35*MOIN*%
%IR0*IPPOS*OFA0.00000B0.00000*MIA0B0*SFA1.00000B1.00000*%
%AMMACRO19*
4,1,16,.09696,-.02,
.092014,-.036533,
.084272,-.051956,
.07397,-.065801,
.06142,-.077646,
.047004,-.087131,
.031159,-.09397,
.02,-.09696,
.02,-.10206,
.037419,-.097037,
.0537,-.089065,
.068351,-.078387,
.080924,-.065327,
.091038,-.050282,
.098387,-.033709,
.10206,-.02,
.09696,-.02,
90.*
4,1,16,-.02,-.09696,
-.036533,-.092014,
-.051956,-.084272,
-.065801,-.07397,
-.077646,-.06142,
-.087131,-.047004,
-.09397,-.031159,
-.09696,-.02,
-.10206,-.02,
-.097037,-.037419,
-.089065,-.0537,
-.078387,-.068351,
-.065327,-.080924,
-.050282,-.091038,
-.033709,-.098387,
-.02,-.10206,
-.02,-.09696,
90.*
4,1,16,-.09696,.02,
-.092014,.036533,
-.084272,.051956,
-.07397,.065801,
-.06142,.077646,
-.047004,.087131,
-.031159,.09397,
-.02,.09696,
-.02,.10206,
-.037419,.097037,
-.0537,.089065,
-.068351,.078387,
-.080924,.065327,
-.091038,.050282,
-.098387,.033709,
-.10206,.02,
-.09696,.02,
90.*
4,1,16,.02,.09696,
.036533,.092014,
.051956,.084272,
.065801,.07397,
.077646,.06142,
.087131,.047004,
.09397,.031159,
.09696,.02,
.10206,.02,
.097037,.037419,
.089065,.0537,
.078387,.068351,
.065327,.080924,
.050282,.091038,
.033709,.098387,
.02,.10206,
.02,.09696,
90.*
%
%ADD19MACRO19*%
%AMMACRO40*
4,1,13,.02632,.01218,
.028035,.007425,
.028899,.002443,
.028884,-.002612,
.027991,-.007588,
.02632,-.01218,
.03005,-.01591,
.032356,-.01045,
.033679,-.004673,
.033979,.001247,
.033246,.007128,
.031504,.012793,
.03005,.01591,
.02632,.01218,
90.*
4,1,13,.01218,-.02632,
.007425,-.028035,
.002443,-.028899,
-.002612,-.028884,
-.007588,-.027991,
-.01218,-.02632,
-.01591,-.03005,
-.01045,-.032356,
-.004673,-.033679,
.001247,-.033979,
.007128,-.033246,
.012793,-.031504,
.01591,-.03005,
.01218,-.02632,
90.*
4,1,13,-.02632,-.01218,
-.028035,-.007425,
-.028899,-.002443,
-.028884,.002612,
-.027991,.007588,
-.02632,.01218,
-.03005,.01591,
-.032356,.01045,
-.033679,.004673,
-.033979,-.001247,
-.033246,-.007128,
-.031504,-.012793,
-.03005,-.01591,
-.02632,-.01218,
90.*
4,1,13,-.01218,.02632,
-.007425,.028035,
-.002443,.028899,
.002612,.028884,
.007588,.027991,
.01218,.02632,
.01591,.03005,
.01045,.032356,
.004673,.033679,
-.001247,.033979,
-.007128,.033246,
-.012793,.031504,
-.01591,.03005,
-.01218,.02632,
90.*
%
%ADD40MACRO40*%
%AMMACRO29*
4,1,13,.02632,.01218,
.028035,.007425,
.028899,.002443,
.028884,-.002612,
.027991,-.007588,
.02632,-.01218,
.03005,-.01591,
.032356,-.01045,
.033679,-.004673,
.033979,.001247,
.033246,.007128,
.031504,.012793,
.03005,.01591,
.02632,.01218,
0.0*
4,1,13,.01218,-.02632,
.007425,-.028035,
.002443,-.028899,
-.002612,-.028884,
-.007588,-.027991,
-.01218,-.02632,
-.01591,-.03005,
-.01045,-.032356,
-.004673,-.033679,
.001247,-.033979,
.007128,-.033246,
.012793,-.031504,
.01591,-.03005,
.01218,-.02632,
0.0*
4,1,13,-.02632,-.01218,
-.028035,-.007425,
-.028899,-.002443,
-.028884,.002612,
-.027991,.007588,
-.02632,.01218,
-.03005,.01591,
-.032356,.01045,
-.033679,.004673,
-.033979,-.001247,
-.033246,-.007128,
-.031504,-.012793,
-.03005,-.01591,
-.02632,-.01218,
0.0*
4,1,13,-.01218,.02632,
-.007425,.028035,
-.002443,.028899,
.002612,.028884,
.007588,.027991,
.01218,.02632,
.01591,.03005,
.01045,.032356,
.004673,.033679,
-.001247,.033979,
-.007128,.033246,
-.012793,.031504,
-.01591,.03005,
-.01218,.02632,
0.0*
%
%ADD29MACRO29*%
%ADD14C,.03*%
%ADD24C,.032*%
%ADD21C,.06*%
%ADD36C,.043*%
%ADD32C,.07*%
%ADD38C,.063*%
%ADD26C,.036*%
%ADD25C,.028*%
%ADD18C,.064*%
%ADD23C,.066*%
%ADD31C,.058*%
%ADD28C,.068*%
%ADD12C,.078*%
%AMMACRO34*
4,1,14,.02707,.01293,
.028904,.008033,
.02986,.002892,
.029908,-.002337,
.029048,-.007495,
.027305,-.012426,
.02707,-.01293,
.03079,-.01665,
.033213,-.01105,
.034628,-.005115,
.03499,.000976,
.034289,.007037,
.032546,.012884,
.03079,.01665,
.02707,.01293,
270.*
4,1,14,.01293,-.02707,
.008033,-.028904,
.002892,-.02986,
-.002337,-.029908,
-.007495,-.029048,
-.012426,-.027305,
-.01293,-.02707,
-.01665,-.03079,
-.01105,-.033213,
-.005115,-.034628,
.000976,-.03499,
.007037,-.034289,
.012884,-.032546,
.01665,-.03079,
.01293,-.02707,
270.*
4,1,14,-.02707,-.01293,
-.028904,-.008033,
-.02986,-.002892,
-.029908,.002337,
-.029048,.007495,
-.027305,.012426,
-.02707,.01293,
-.03079,.01665,
-.033213,.01105,
-.034628,.005115,
-.03499,-.000976,
-.034289,-.007037,
-.032546,-.012884,
-.03079,-.01665,
-.02707,-.01293,
270.*
4,1,14,-.01293,.02707,
-.008033,.028904,
-.002892,.02986,
.002337,.029908,
.007495,.029048,
.012426,.027305,
.01293,.02707,
.01665,.03079,
.01105,.033213,
.005115,.034628,
-.000976,.03499,
-.007037,.034289,
-.012884,.032546,
-.01665,.03079,
-.01293,.02707,
270.*
%
%ADD34MACRO34*%
%AMMACRO20*
4,1,15,.00398,.00044,
.003999,.000208,
.004004,-.000025,
.003996,-.000258,
.00398,-.00044,
.00483,-.00129,
.004897,-.001007,
.004947,-.000721,
.004981,-.000432,
.004997,-.000141,
.004997,.000149,
.00498,.00044,
.004946,.000729,
.004895,.001015,
.00483,.00129,
.00398,.00044,
90.*
4,1,15,.00044,-.00398,
.000208,-.003999,
-.000025,-.004004,
-.000258,-.003996,
-.00044,-.00398,
-.00129,-.00483,
-.001007,-.004897,
-.000721,-.004947,
-.000432,-.004981,
-.000141,-.004997,
.000149,-.004997,
.00044,-.00498,
.000729,-.004946,
.001015,-.004895,
.00129,-.00483,
.00044,-.00398,
90.*
4,1,15,-.00398,-.00044,
-.003999,-.000208,
-.004004,.000025,
-.003996,.000258,
-.00398,.00044,
-.00483,.00129,
-.004897,.001007,
-.004947,.000721,
-.004981,.000432,
-.004997,.000141,
-.004997,-.000149,
-.00498,-.00044,
-.004946,-.000729,
-.004895,-.001015,
-.00483,-.00129,
-.00398,-.00044,
90.*
4,1,15,-.00044,.00398,
-.000208,.003999,
.000025,.004004,
.000258,.003996,
.00044,.00398,
.00129,.00483,
.001007,.004897,
.000721,.004947,
.000432,.004981,
.000141,.004997,
-.000149,.004997,
-.00044,.00498,
-.000729,.004946,
-.001015,.004895,
-.00129,.00483,
-.00044,.00398,
90.*
%
%ADD20MACRO20*%
%AMMACRO11*
4,1,15,.00398,.00044,
.003999,.000208,
.004004,-.000025,
.003996,-.000258,
.00398,-.00044,
.00483,-.00129,
.004897,-.001007,
.004947,-.000721,
.004981,-.000432,
.004997,-.000141,
.004997,.000149,
.00498,.00044,
.004946,.000729,
.004895,.001015,
.00483,.00129,
.00398,.00044,
0.0*
4,1,15,.00044,-.00398,
.000208,-.003999,
-.000025,-.004004,
-.000258,-.003996,
-.00044,-.00398,
-.00129,-.00483,
-.001007,-.004897,
-.000721,-.004947,
-.000432,-.004981,
-.000141,-.004997,
.000149,-.004997,
.00044,-.00498,
.000729,-.004946,
.001015,-.004895,
.00129,-.00483,
.00044,-.00398,
0.0*
4,1,15,-.00398,-.00044,
-.003999,-.000208,
-.004004,.000025,
-.003996,.000258,
-.00398,.00044,
-.00483,.00129,
-.004897,.001007,
-.004947,.000721,
-.004981,.000432,
-.004997,.000141,
-.004997,-.000149,
-.00498,-.00044,
-.004946,-.000729,
-.004895,-.001015,
-.00483,-.00129,
-.00398,-.00044,
0.0*
4,1,15,-.00044,.00398,
-.000208,.003999,
.000025,.004004,
.000258,.003996,
.00044,.00398,
.00129,.00483,
.001007,.004897,
.000721,.004947,
.000432,.004981,
.000141,.004997,
-.000149,.004997,
-.00044,.00498,
-.000729,.004946,
-.001015,.004895,
-.00129,.00483,
-.00044,.00398,
0.0*
%
%ADD11MACRO11*%
%AMMACRO39*
4,1,13,.02442,.01028,
.025834,.005883,
.026463,.001308,
.026288,-.003307,
.025315,-.007822,
.02442,-.01028,
.02819,-.01405,
.030201,-.008941,
.031295,-.003561,
.031438,.001927,
.030626,.007357,
.028883,.012564,
.02819,.01405,
.02442,.01028,
180.*
4,1,13,.01028,-.02442,
.005883,-.025834,
.001308,-.026463,
-.003307,-.026288,
-.007822,-.025315,
-.01028,-.02442,
-.01405,-.02819,
-.008941,-.030201,
-.003561,-.031295,
.001927,-.031438,
.007357,-.030626,
.012564,-.028883,
.01405,-.02819,
.01028,-.02442,
180.*
4,1,13,-.02442,-.01028,
-.025834,-.005883,
-.026463,-.001308,
-.026288,.003307,
-.025315,.007822,
-.02442,.01028,
-.02819,.01405,
-.030201,.008941,
-.031295,.003561,
-.031438,-.001927,
-.030626,-.007357,
-.028883,-.012564,
-.02819,-.01405,
-.02442,-.01028,
180.*
4,1,13,-.01028,.02442,
-.005883,.025834,
-.001308,.026463,
.003307,.026288,
.007822,.025315,
.01028,.02442,
.01405,.02819,
.008941,.030201,
.003561,.031295,
-.001927,.031438,
-.007357,.030626,
-.012564,.028883,
-.01405,.02819,
-.01028,.02442,
180.*
%
%ADD39MACRO39*%
%AMMACRO37*
4,1,13,.02632,.01218,
.028035,.007425,
.028899,.002443,
.028884,-.002612,
.027991,-.007588,
.02632,-.01218,
.03005,-.01591,
.032356,-.01045,
.033679,-.004673,
.033979,.001247,
.033246,.007128,
.031504,.012793,
.03005,.01591,
.02632,.01218,
270.*
4,1,13,.01218,-.02632,
.007425,-.028035,
.002443,-.028899,
-.002612,-.028884,
-.007588,-.027991,
-.01218,-.02632,
-.01591,-.03005,
-.01045,-.032356,
-.004673,-.033679,
.001247,-.033979,
.007128,-.033246,
.012793,-.031504,
.01591,-.03005,
.01218,-.02632,
270.*
4,1,13,-.02632,-.01218,
-.028035,-.007425,
-.028899,-.002443,
-.028884,.002612,
-.027991,.007588,
-.02632,.01218,
-.03005,.01591,
-.032356,.01045,
-.033679,.004673,
-.033979,-.001247,
-.033246,-.007128,
-.031504,-.012793,
-.03005,-.01591,
-.02632,-.01218,
270.*
4,1,13,-.01218,.02632,
-.007425,.028035,
-.002443,.028899,
.002612,.028884,
.007588,.027991,
.01218,.02632,
.01591,.03005,
.01045,.032356,
.004673,.033679,
-.001247,.033979,
-.007128,.033246,
-.012793,.031504,
-.01591,.03005,
-.01218,.02632,
270.*
%
%ADD37MACRO37*%
%AMMACRO33*
4,1,13,.02632,.01218,
.028035,.007425,
.028899,.002443,
.028884,-.002612,
.027991,-.007588,
.02632,-.01218,
.03005,-.01591,
.032356,-.01045,
.033679,-.004673,
.033979,.001247,
.033246,.007128,
.031504,.012793,
.03005,.01591,
.02632,.01218,
180.*
4,1,13,.01218,-.02632,
.007425,-.028035,
.002443,-.028899,
-.002612,-.028884,
-.007588,-.027991,
-.01218,-.02632,
-.01591,-.03005,
-.01045,-.032356,
-.004673,-.033679,
.001247,-.033979,
.007128,-.033246,
.012793,-.031504,
.01591,-.03005,
.01218,-.02632,
180.*
4,1,13,-.02632,-.01218,
-.028035,-.007425,
-.028899,-.002443,
-.028884,.002612,
-.027991,.007588,
-.02632,.01218,
-.03005,.01591,
-.032356,.01045,
-.033679,.004673,
-.033979,-.001247,
-.033246,-.007128,
-.031504,-.012793,
-.03005,-.01591,
-.02632,-.01218,
180.*
4,1,13,-.01218,.02632,
-.007425,.028035,
-.002443,.028899,
.002612,.028884,
.007588,.027991,
.01218,.02632,
.01591,.03005,
.01045,.032356,
.004673,.033679,
-.001247,.033979,
-.007128,.033246,
-.012793,.031504,
-.01591,.03005,
-.01218,.02632,
180.*
%
%ADD33MACRO33*%
%ADD10C,.114*%
%ADD16C,.19*%
%ADD22C,.119*%
%ADD17C,.156*%
%ADD30C,.166*%
%AMMACRO15*
4,1,15,.00398,.00044,
.003999,.000208,
.004004,-.000025,
.003996,-.000258,
.00398,-.00044,
.00483,-.00129,
.004897,-.001007,
.004947,-.000721,
.004981,-.000432,
.004997,-.000141,
.004997,.000149,
.00498,.00044,
.004946,.000729,
.004895,.001015,
.00483,.00129,
.00398,.00044,
270.*
4,1,15,.00044,-.00398,
.000208,-.003999,
-.000025,-.004004,
-.000258,-.003996,
-.00044,-.00398,
-.00129,-.00483,
-.001007,-.004897,
-.000721,-.004947,
-.000432,-.004981,
-.000141,-.004997,
.000149,-.004997,
.00044,-.00498,
.000729,-.004946,
.001015,-.004895,
.00129,-.00483,
.00044,-.00398,
270.*
4,1,15,-.00398,-.00044,
-.003999,-.000208,
-.004004,.000025,
-.003996,.000258,
-.00398,.00044,
-.00483,.00129,
-.004897,.001007,
-.004947,.000721,
-.004981,.000432,
-.004997,.000141,
-.004997,-.000149,
-.00498,-.00044,
-.004946,-.000729,
-.004895,-.001015,
-.00483,-.00129,
-.00398,-.00044,
270.*
4,1,15,-.00044,.00398,
-.000208,.003999,
.000025,.004004,
.000258,.003996,
.00044,.00398,
.00129,.00483,
.001007,.004897,
.000721,.004947,
.000432,.004981,
.000141,.004997,
-.000149,.004997,
-.00044,.00498,
-.000729,.004946,
-.001015,.004895,
-.00129,.00483,
-.00044,.00398,
270.*
%
%ADD15MACRO15*%
%AMMACRO35*
4,1,14,.05302,.02473,
.056509,.015147,
.058281,.005105,
.058282,-.005093,
.056512,-.015136,
.053025,-.02472,
.05302,-.02473,
.05676,-.02847,
.060841,-.018181,
.063074,-.00734,
.063391,.003724,
.061781,.014675,
.058294,.025181,
.05676,.02847,
.05302,.02473,
0.0*
4,1,14,.02473,-.05302,
.015147,-.056509,
.005105,-.058281,
-.005093,-.058282,
-.015136,-.056512,
-.02472,-.053025,
-.02473,-.05302,
-.02847,-.05676,
-.018181,-.060841,
-.00734,-.063074,
.003724,-.063391,
.014675,-.061781,
.025181,-.058294,
.02847,-.05676,
.02473,-.05302,
0.0*
4,1,14,-.05302,-.02473,
-.056509,-.015147,
-.058281,-.005105,
-.058282,.005093,
-.056512,.015136,
-.053025,.02472,
-.05302,.02473,
-.05676,.02847,
-.060841,.018181,
-.063074,.00734,
-.063391,-.003724,
-.061781,-.014675,
-.058294,-.025181,
-.05676,-.02847,
-.05302,-.02473,
0.0*
4,1,14,-.02473,.05302,
-.015147,.056509,
-.005105,.058281,
.005093,.058282,
.015136,.056512,
.02472,.053025,
.02473,.05302,
.02847,.05676,
.018181,.060841,
.00734,.063074,
-.003724,.063391,
-.014675,.061781,
-.025181,.058294,
-.02847,.05676,
-.02473,.05302,
0.0*
%
%ADD35MACRO35*%
%AMMACRO13*
4,1,13,.03683,.01561,
.038981,.008977,
.039948,.002072,
.039701,-.004896,
.038247,-.011716,
.03683,-.01561,
.04061,-.01939,
.04336,-.012044,
.044793,-.004331,
.044864,.003513,
.043573,.01125,
.040957,.018645,
.04061,.01939,
.03683,.01561,
0.0*
4,1,13,.01561,-.03683,
.008977,-.038981,
.002072,-.039948,
-.004896,-.039701,
-.011716,-.038247,
-.01561,-.03683,
-.01939,-.04061,
-.012044,-.04336,
-.004331,-.044793,
.003513,-.044864,
.01125,-.043573,
.018645,-.040957,
.01939,-.04061,
.01561,-.03683,
0.0*
4,1,13,-.03683,-.01561,
-.038981,-.008977,
-.039948,-.002072,
-.039701,.004896,
-.038247,.011716,
-.03683,.01561,
-.04061,.01939,
-.04336,.012044,
-.044793,.004331,
-.044864,-.003513,
-.043573,-.01125,
-.040957,-.018645,
-.04061,-.01939,
-.03683,-.01561,
0.0*
4,1,13,-.01561,.03683,
-.008977,.038981,
-.002072,.039948,
.004896,.039701,
.011716,.038247,
.01561,.03683,
.01939,.04061,
.012044,.04336,
.004331,.044793,
-.003513,.044864,
-.01125,.043573,
-.018645,.040957,
-.01939,.04061,
-.01561,.03683,
0.0*
%
%ADD13MACRO13*%
%AMMACRO27*
4,1,13,.02556,.01142,
.027155,.006808,
.027924,.001989,
.027846,-.00289,
.026921,-.007681,
.02556,-.01142,
.02931,-.01517,
.031499,-.00985,
.032731,-.004231,
.032968,.001517,
.032204,.007219,
.030461,.012702,
.02931,.01517,
.02556,.01142,
0.0*
4,1,13,.01142,-.02556,
.006808,-.027155,
.001989,-.027924,
-.00289,-.027846,
-.007681,-.026921,
-.01142,-.02556,
-.01517,-.02931,
-.00985,-.031499,
-.004231,-.032731,
.001517,-.032968,
.007219,-.032204,
.012702,-.030461,
.01517,-.02931,
.01142,-.02556,
0.0*
4,1,13,-.02556,-.01142,
-.027155,-.006808,
-.027924,-.001989,
-.027846,.00289,
-.026921,.007681,
-.02556,.01142,
-.02931,.01517,
-.031499,.00985,
-.032731,.004231,
-.032968,-.001517,
-.032204,-.007219,
-.030461,-.012702,
-.02931,-.01517,
-.02556,-.01142,
0.0*
4,1,13,-.01142,.02556,
-.006808,.027155,
-.001989,.027924,
.00289,.027846,
.007681,.026921,
.01142,.02556,
.01517,.02931,
.00985,.031499,
.004231,.032731,
-.001517,.032968,
-.007219,.032204,
-.012702,.030461,
-.01517,.02931,
-.01142,.02556,
0.0*
%
%ADD27MACRO27*%
%ADD41C,.02*%
%ADD42C,.006*%
%ADD53C,.06204*%
%ADD51C,.06404*%
%ADD47C,.05604*%
%ADD45C,.11004*%
%ADD49C,.3151*%
%ADD46C,.15204*%
%ADD48C,.31532*%
%ADD52C,.31506*%
%ADD50C,.31534*%
%ADD44O,.09222X.04822*%
%ADD43O,.09224X.04824*%
G75*
%LPD*%
G75*
G36*
G01X-6000Y-25685D02*
X1406000D01*
Y903637D01*
X-6000D01*
Y-25685D01*
G37*
%LPC*%
G75*
G36*
G01X3937Y837547D02*
X100000D01*
G03X108122Y845669I0J8122D01*
G01Y870618D01*
X110237D01*
G03X115209Y875590I-1J4973D01*
G01Y883398D01*
X288732D01*
Y876377D01*
G03X288826Y875176I7725J0D01*
G03X295420Y868723I7631J1202D01*
G03X297493I1037J7261D01*
G03X304181Y876378I-1037J7655D01*
G01Y883398D01*
X439909D01*
Y875590D01*
G03X444881Y870618I4973J1D01*
G01X446996D01*
Y845669D01*
G03X455118Y837547I8122J0D01*
G01X517323D01*
G03X525445Y845669I0J8122D01*
G01Y870618D01*
X527560D01*
G03X532532Y875590I-1J4973D01*
G01Y883398D01*
X706055D01*
Y876377D01*
G03X706149Y875176I7725J0D01*
G03X712743Y868723I7631J1202D01*
G03X714816I1037J7261D01*
G03X721504Y876378I-1037J7655D01*
G01Y883398D01*
X857232D01*
Y875590D01*
G03X862204Y870618I4973J1D01*
G01X864319D01*
Y845669D01*
G03X872441Y837547I8122J0D01*
G01X902134D01*
G02X918815Y820866I0J-16681D01*
G01Y650669D01*
G03X926819Y642665I8004J0D01*
G01X983748D01*
G03X991752Y650669I0J8004D01*
G01Y820866D01*
G02X1008433Y837547I16681J0D01*
G01X1013386D01*
G03X1021508Y845669I0J8122D01*
G01Y870618D01*
X1023623D01*
G03X1028595Y875590I-1J4973D01*
G01Y883398D01*
X1202118D01*
Y876377D01*
G03X1202212Y875176I7725J0D01*
G03X1208806Y868723I7631J1202D01*
G03X1210879I1036J7261D01*
G03X1217567Y876378I-1037J7655D01*
G01Y883398D01*
X1353295D01*
Y875590D01*
G03X1358267Y870618I4973J1D01*
G01X1360382D01*
Y845669D01*
G03X1368504Y837547I8122J0D01*
G01X1396063D01*
G02X1396996Y836614I0J-933D01*
G01Y76626D01*
X1396653D01*
G03X1391681Y71654I0J-4972D01*
G01Y40157D01*
G03X1396653Y35185I4972J0D01*
G01X1396996D01*
Y3937D01*
G02X1396063Y3004I-933J0D01*
G01X1310039D01*
G03X1303098Y-3937I0J-6941D01*
G01Y-15748D01*
G02X1302165Y-16681I-933J0D01*
G01X486762D01*
G02X481892Y-11811I0J4870D01*
G01Y-7874D01*
G03X471014Y3004I-10878J0D01*
G01X212402D01*
G02X207532Y7874I0J4870D01*
G01Y94528D01*
G03X196654Y105406I-10878J0D01*
G01X7874D01*
G02X3004Y110276I0J4870D01*
G01Y836614D01*
G02X3937Y837547I933J0D01*
G37*
%LPD*%
G75*
G36*
G01X115226Y418475D02*
X115233Y418468D01*
X112119Y415354D01*
X112115D01*
X112113Y415356D01*
X112107D01*
G02X108619Y418688I-1701J1711D01*
G01X108694Y418775D01*
X108691Y418778D01*
X111807Y421894D01*
X111810Y421891D01*
X111897Y421966D01*
G02X115226Y418475I1621J-1787D01*
G37*
G36*
G01X621794Y85929D02*
X621802Y85934D01*
X624757Y80419D01*
X624754Y80416D01*
X624751Y80414D01*
X624779Y80355D01*
G02X620463Y77990I-2202J-1102D01*
G01X620402Y78084D01*
X620399Y78082D01*
X617444Y83599D01*
X617447Y83601D01*
X617407Y83691D01*
G02X621794Y85929I2217J1073D01*
G37*
G36*
G01X542707Y77990D02*
X542646Y78084D01*
X542643Y78082D01*
X539688Y83597D01*
X539691Y83600D01*
X539694Y83602D01*
X539666Y83661D01*
G02X544038Y85929I2202J1103D01*
G01X544046Y85934D01*
X547001Y80417D01*
X546998Y80415D01*
X547038Y80325D01*
G02X542707Y77990I-2217J-1072D01*
G37*
G36*
G01X1343726Y873166D02*
X1340525D01*
G02X1340526Y877186I1J2010D01*
G01X1343726D01*
G02Y873166I0J-2010D01*
G37*
G36*
G01X1331128D02*
X1327928D01*
G02Y877186I0J2010D01*
G01X1331129D01*
G02X1331128Y873166I-1J-2010D01*
G37*
G36*
G01X1318529D02*
X1315329D01*
G02Y877186I0J2010D01*
G01X1318530D01*
G02X1318529Y873166I-1J-2010D01*
G37*
G36*
G01X1305931D02*
X1302731D01*
G02Y877186I0J2010D01*
G01X1305932D01*
G02X1305931Y873166I-1J-2010D01*
G37*
G36*
G01X1293333D02*
X1290133D01*
G02Y877186I0J2010D01*
G01X1293334D01*
G02X1293333Y873166I-1J-2010D01*
G37*
G36*
G01X1280734D02*
X1277534D01*
G02Y877186I0J2010D01*
G01X1280735D01*
G02X1280734Y873166I-1J-2010D01*
G37*
G36*
G01X1268136D02*
X1264936D01*
G02Y877186I0J2010D01*
G01X1268137D01*
G02X1268136Y873166I-1J-2010D01*
G37*
G36*
G01X1255537D02*
X1252337D01*
G02Y877186I0J2010D01*
G01X1255538D01*
G02X1255537Y873166I-1J-2010D01*
G37*
G36*
G01X1242939D02*
X1239739D01*
G02Y877186I0J2010D01*
G01X1242940D01*
G02X1242939Y873166I-1J-2010D01*
G37*
G36*
G01X1230340D02*
X1227140D01*
G02Y877186I0J2010D01*
G01X1230341D01*
G02X1230340Y873166I-1J-2010D01*
G37*
G36*
G01X1186246D02*
X1183046D01*
G02Y877186I0J2010D01*
G01X1186247D01*
G02X1186246Y873166I-1J-2010D01*
G37*
G36*
G01X1164199D02*
X1160999D01*
G02Y877186I0J2010D01*
G01X1164200D01*
G02X1164199Y873166I-1J-2010D01*
G37*
G36*
G01X1151600D02*
X1148400D01*
G02Y877186I0J2010D01*
G01X1151601D01*
G02X1151600Y873166I-1J-2010D01*
G37*
G36*
G01X1139002D02*
X1135802D01*
G02Y877186I0J2010D01*
G01X1139003D01*
G02X1139002Y873166I-1J-2010D01*
G37*
G36*
G01X1126403D02*
X1123203D01*
G02Y877186I0J2010D01*
G01X1126404D01*
G02X1126403Y873166I-1J-2010D01*
G37*
G36*
G01X1113805D02*
X1110605D01*
G02Y877186I0J2010D01*
G01X1113806D01*
G02X1113805Y873166I-1J-2010D01*
G37*
G36*
G01X1101207D02*
X1098007D01*
G02Y877186I0J2010D01*
G01X1101208D01*
G02X1101207Y873166I-1J-2010D01*
G37*
G36*
G01X1088608D02*
X1085408D01*
G02Y877186I0J2010D01*
G01X1088609D01*
G02X1088608Y873166I-1J-2010D01*
G37*
G36*
G01X1076010D02*
X1072810D01*
G02Y877186I0J2010D01*
G01X1076011D01*
G02X1076010Y873166I-1J-2010D01*
G37*
G36*
G01X1050813D02*
X1047613D01*
G02Y877186I0J2010D01*
G01X1050814D01*
G02X1050813Y873166I-1J-2010D01*
G37*
G36*
G01X1038214D02*
X1035014D01*
G02Y877186I0J2010D01*
G01X1038215D01*
G02X1038214Y873166I-1J-2010D01*
G37*
G36*
G01X847663D02*
X844463D01*
G02Y877186I0J2010D01*
G01X847664D01*
G02X847663Y873166I-1J-2010D01*
G37*
G36*
G01X835065D02*
X831865D01*
G02Y877186I0J2010D01*
G01X835066D01*
G02X835065Y873166I-1J-2010D01*
G37*
G36*
G01X809868D02*
X806668D01*
G02Y877186I0J2010D01*
G01X809869D01*
G02X809868Y873166I-1J-2010D01*
G37*
G36*
G01X797270D02*
X794070D01*
G02Y877186I0J2010D01*
G01X797271D01*
G02X797270Y873166I-1J-2010D01*
G37*
G36*
G01X784671D02*
X781471D01*
G02Y877186I0J2010D01*
G01X784672D01*
G02X784671Y873166I-1J-2010D01*
G37*
G36*
G01X772073D02*
X768873D01*
G02Y877186I0J2010D01*
G01X772074D01*
G02X772073Y873166I-1J-2010D01*
G37*
G36*
G01X759474D02*
X756274D01*
G02Y877186I0J2010D01*
G01X759475D01*
G02X759474Y873166I-1J-2010D01*
G37*
G36*
G01X746876D02*
X743676D01*
G02Y877186I0J2010D01*
G01X746877D01*
G02X746876Y873166I-1J-2010D01*
G37*
G36*
G01X734277D02*
X731076D01*
G02X731077Y877186I1J2010D01*
G01X734277D01*
G02Y873166I0J-2010D01*
G37*
G36*
G01X690183D02*
X686983D01*
G02Y877186I0J2010D01*
G01X690184D01*
G02X690183Y873166I-1J-2010D01*
G37*
G36*
G01X677585D02*
X674385D01*
G02Y877186I0J2010D01*
G01X677586D01*
G02X677585Y873166I-1J-2010D01*
G37*
G36*
G01X664986D02*
X661786D01*
G02Y877186I0J2010D01*
G01X664987D01*
G02X664986Y873166I-1J-2010D01*
G37*
G36*
G01X652388D02*
X649188D01*
G02Y877186I0J2010D01*
G01X652389D01*
G02X652388Y873166I-1J-2010D01*
G37*
G36*
G01X630340D02*
X627140D01*
G02Y877186I0J2010D01*
G01X630341D01*
G02X630340Y873166I-1J-2010D01*
G37*
G36*
G01X617742D02*
X614542D01*
G02Y877186I0J2010D01*
G01X617743D01*
G02X617742Y873166I-1J-2010D01*
G37*
G36*
G01X605144D02*
X601944D01*
G02Y877186I0J2010D01*
G01X605145D01*
G02X605144Y873166I-1J-2010D01*
G37*
G36*
G01X592545D02*
X589345D01*
G02Y877186I0J2010D01*
G01X592546D01*
G02X592545Y873166I-1J-2010D01*
G37*
G36*
G01X579947D02*
X576747D01*
G02Y877186I0J2010D01*
G01X579948D01*
G02X579947Y873166I-1J-2010D01*
G37*
G36*
G01X567348D02*
X564148D01*
G02Y877186I0J2010D01*
G01X567349D01*
G02X567348Y873166I-1J-2010D01*
G37*
G36*
G01X554750D02*
X551550D01*
G02Y877186I0J2010D01*
G01X554751D01*
G02X554750Y873166I-1J-2010D01*
G37*
G36*
G01X542151D02*
X538951D01*
G02Y877186I0J2010D01*
G01X542152D01*
G02X542151Y873166I-1J-2010D01*
G37*
G36*
G01X420891D02*
X417691D01*
G02Y877186I0J2010D01*
G01X420892D01*
G02X420891Y873166I-1J-2010D01*
G37*
G36*
G01X408292D02*
X405092D01*
G02Y877186I0J2010D01*
G01X408293D01*
G02X408292Y873166I-1J-2010D01*
G37*
G36*
G01X395694D02*
X392494D01*
G02Y877186I0J2010D01*
G01X395695D01*
G02X395694Y873166I-1J-2010D01*
G37*
G36*
G01X383096D02*
X379896D01*
G02Y877186I0J2010D01*
G01X383097D01*
G02X383096Y873166I-1J-2010D01*
G37*
G36*
G01X361048D02*
X357848D01*
G02Y877186I0J2010D01*
G01X361049D01*
G02X361048Y873166I-1J-2010D01*
G37*
G36*
G01X348450D02*
X345250D01*
G02Y877186I0J2010D01*
G01X348451D01*
G02X348450Y873166I-1J-2010D01*
G37*
G36*
G01X335851D02*
X332651D01*
G02Y877186I0J2010D01*
G01X335852D01*
G02X335851Y873166I-1J-2010D01*
G37*
G36*
G01X323253D02*
X320053D01*
G02Y877186I0J2010D01*
G01X323254D01*
G02X323253Y873166I-1J-2010D01*
G37*
G36*
G01X272859D02*
X269659D01*
G02Y877186I0J2010D01*
G01X272860D01*
G02X272859Y873166I-1J-2010D01*
G37*
G36*
G01X260261D02*
X257061D01*
G02Y877186I0J2010D01*
G01X260262D01*
G02X260261Y873166I-1J-2010D01*
G37*
G36*
G01X238213D02*
X235013D01*
G02Y877186I0J2010D01*
G01X238214D01*
G02X238213Y873166I-1J-2010D01*
G37*
G36*
G01X225615D02*
X222415D01*
G02Y877186I0J2010D01*
G01X225616D01*
G02X225615Y873166I-1J-2010D01*
G37*
G36*
G01X213017D02*
X209817D01*
G02Y877186I0J2010D01*
G01X213018D01*
G02X213017Y873166I-1J-2010D01*
G37*
G36*
G01X200418Y869666D02*
X197218D01*
G02Y873686I0J2010D01*
G01X200419D01*
G02X200418Y869666I-1J-2010D01*
G37*
G36*
G01X702400Y866790D02*
X699200D01*
G02Y870810I0J2010D01*
G01X702401D01*
G02X702400Y866790I-1J-2010D01*
G37*
G36*
G01X1198937Y865191D02*
Y865181D01*
X1195737Y865281D01*
Y865283D01*
X1195561Y865304D01*
G02X1195863Y869309I238J1996D01*
G01Y869319D01*
X1199062Y869219D01*
X1199071Y869210D01*
X1199145Y869205D01*
G02X1198937Y865191I-145J-2005D01*
G37*
G36*
G01X285500Y864190D02*
X282300D01*
G02Y868210I0J2010D01*
G01X285501D01*
G02X285500Y864190I-1J-2010D01*
G37*
G36*
G01X310955Y863666D02*
X307755D01*
G02Y867686I0J2010D01*
G01X310956D01*
G02X310955Y863666I-1J-2010D01*
G37*
G36*
G01X1350025Y828291D02*
X1346825D01*
G02Y832311I0J2010D01*
G01X1350026D01*
G02X1350025Y828291I-1J-2010D01*
G37*
G36*
G01X1337427D02*
X1334227D01*
G02Y832311I0J2010D01*
G01X1337428D01*
G02X1337427Y828291I-1J-2010D01*
G37*
G36*
G01X1324829D02*
X1321628D01*
G02X1321629Y832311I1J2010D01*
G01X1324829D01*
G02Y828291I0J-2010D01*
G37*
G36*
G01X1312231D02*
X1309030D01*
G02X1309031Y832311I1J2010D01*
G01X1312231D01*
G02Y828291I0J-2010D01*
G37*
G36*
G01X1287033D02*
X1283832D01*
G02X1283833Y832311I1J2010D01*
G01X1287033D01*
G02Y828291I0J-2010D01*
G37*
G36*
G01X1274435D02*
X1271234D01*
G02X1271235Y832311I1J2010D01*
G01X1274435D01*
G02Y828291I0J-2010D01*
G37*
G36*
G01X1261837D02*
X1258636D01*
G02X1258637Y832311I1J2010D01*
G01X1261837D01*
G02Y828291I0J-2010D01*
G37*
G36*
G01X1249239D02*
X1246038D01*
G02X1246039Y832311I1J2010D01*
G01X1249239D01*
G02Y828291I0J-2010D01*
G37*
G36*
G01X1236640D02*
X1233439D01*
G02X1233440Y832311I1J2010D01*
G01X1236640D01*
G02Y828291I0J-2010D01*
G37*
G36*
G01X1224042D02*
X1220842D01*
G02Y832311I0J2010D01*
G01X1224043D01*
G02X1224042Y828291I-1J-2010D01*
G37*
G36*
G01X1192545D02*
X1189344D01*
G02X1189345Y832311I1J2010D01*
G01X1192545D01*
G02Y828291I0J-2010D01*
G37*
G36*
G01X1179947D02*
X1176746D01*
G02X1176747Y832311I1J2010D01*
G01X1179947D01*
G02Y828291I0J-2010D01*
G37*
G36*
G01X1157899D02*
X1154698D01*
G02X1154699Y832311I1J2010D01*
G01X1157899D01*
G02Y828291I0J-2010D01*
G37*
G36*
G01X1145301D02*
X1142100D01*
G02X1142101Y832311I1J2010D01*
G01X1145301D01*
G02Y828291I0J-2010D01*
G37*
G36*
G01X1132703D02*
X1129503D01*
G02Y832311I0J2010D01*
G01X1132704D01*
G02X1132703Y828291I-1J-2010D01*
G37*
G36*
G01X1120104D02*
X1116903D01*
G02X1116904Y832311I1J2010D01*
G01X1120104D01*
G02Y828291I0J-2010D01*
G37*
G36*
G01X1107506D02*
X1104305D01*
G02X1104306Y832311I1J2010D01*
G01X1107506D01*
G02Y828291I0J-2010D01*
G37*
G36*
G01X1094907D02*
X1091706D01*
G02X1091707Y832311I1J2010D01*
G01X1094907D01*
G02Y828291I0J-2010D01*
G37*
G36*
G01X1082309D02*
X1079108D01*
G02X1079109Y832311I1J2010D01*
G01X1082309D01*
G02Y828291I0J-2010D01*
G37*
G36*
G01X1069711D02*
X1066510D01*
G02X1066511Y832311I1J2010D01*
G01X1069711D01*
G02Y828291I0J-2010D01*
G37*
G36*
G01X1057112D02*
X1053911D01*
G02X1053912Y832311I1J2010D01*
G01X1057112D01*
G02Y828291I0J-2010D01*
G37*
G36*
G01X1044514D02*
X1041313D01*
G02X1041314Y832311I1J2010D01*
G01X1044514D01*
G02Y828291I0J-2010D01*
G37*
G36*
G01X853962D02*
X850761D01*
G02X850762Y832311I1J2010D01*
G01X853962D01*
G02Y828291I0J-2010D01*
G37*
G36*
G01X841364D02*
X838163D01*
G02X838164Y832311I1J2010D01*
G01X841364D01*
G02Y828291I0J-2010D01*
G37*
G36*
G01X816167D02*
X812966D01*
G02X812967Y832311I1J2010D01*
G01X816167D01*
G02Y828291I0J-2010D01*
G37*
G36*
G01X803569D02*
X800368D01*
G02X800369Y832311I1J2010D01*
G01X803569D01*
G02Y828291I0J-2010D01*
G37*
G36*
G01X790970D02*
X787769D01*
G02X787770Y832311I1J2010D01*
G01X790970D01*
G02Y828291I0J-2010D01*
G37*
G36*
G01X778372D02*
X775171D01*
G02X775172Y832311I1J2010D01*
G01X778372D01*
G02Y828291I0J-2010D01*
G37*
G36*
G01X765774D02*
X762573D01*
G02X762574Y832311I1J2010D01*
G01X765774D01*
G02Y828291I0J-2010D01*
G37*
G36*
G01X753175D02*
X749974D01*
G02X749975Y832311I1J2010D01*
G01X753175D01*
G02Y828291I0J-2010D01*
G37*
G36*
G01X740577D02*
X737376D01*
G02X737377Y832311I1J2010D01*
G01X740577D01*
G02Y828291I0J-2010D01*
G37*
G36*
G01X727978D02*
X724777D01*
G02X724778Y832311I1J2010D01*
G01X727978D01*
G02Y828291I0J-2010D01*
G37*
G36*
G01X696482D02*
X693281D01*
G02X693282Y832311I1J2010D01*
G01X696482D01*
G02Y828291I0J-2010D01*
G37*
G36*
G01X683884D02*
X680683D01*
G02X680684Y832311I1J2010D01*
G01X683884D01*
G02Y828291I0J-2010D01*
G37*
G36*
G01X671285D02*
X668084D01*
G02X668085Y832311I1J2010D01*
G01X671285D01*
G02Y828291I0J-2010D01*
G37*
G36*
G01X658687D02*
X655486D01*
G02X655487Y832311I1J2010D01*
G01X658687D01*
G02Y828291I0J-2010D01*
G37*
G36*
G01X636640D02*
X633439D01*
G02X633440Y832311I1J2010D01*
G01X636640D01*
G02Y828291I0J-2010D01*
G37*
G36*
G01X624042D02*
X620841D01*
G02X620842Y832311I1J2010D01*
G01X624042D01*
G02Y828291I0J-2010D01*
G37*
G36*
G01X611443D02*
X608242D01*
G02X608243Y832311I1J2010D01*
G01X611443D01*
G02Y828291I0J-2010D01*
G37*
G36*
G01X598845D02*
X595644D01*
G02X595645Y832311I1J2010D01*
G01X598845D01*
G02Y828291I0J-2010D01*
G37*
G36*
G01X586246D02*
X583045D01*
G02X583046Y832311I1J2010D01*
G01X586246D01*
G02Y828291I0J-2010D01*
G37*
G36*
G01X573648D02*
X570447D01*
G02X570448Y832311I1J2010D01*
G01X573648D01*
G02Y828291I0J-2010D01*
G37*
G36*
G01X561050D02*
X557849D01*
G02X557850Y832311I1J2010D01*
G01X561050D01*
G02Y828291I0J-2010D01*
G37*
G36*
G01X548451D02*
X545250D01*
G02X545251Y832311I1J2010D01*
G01X548451D01*
G02Y828291I0J-2010D01*
G37*
G36*
G01X427191D02*
X423990D01*
G02X423991Y832311I1J2010D01*
G01X427191D01*
G02Y828291I0J-2010D01*
G37*
G36*
G01X414593D02*
X411392D01*
G02X411393Y832311I1J2010D01*
G01X414593D01*
G02Y828291I0J-2010D01*
G37*
G36*
G01X401994D02*
X398794D01*
G02Y832311I0J2010D01*
G01X401995D01*
G02X401994Y828291I-1J-2010D01*
G37*
G36*
G01X389396D02*
X386195D01*
G02X386196Y832311I1J2010D01*
G01X389396D01*
G02Y828291I0J-2010D01*
G37*
G36*
G01X367348D02*
X364147D01*
G02X364148Y832311I1J2010D01*
G01X367348D01*
G02Y828291I0J-2010D01*
G37*
G36*
G01X354750D02*
X351549D01*
G02X351550Y832311I1J2010D01*
G01X354750D01*
G02Y828291I0J-2010D01*
G37*
G36*
G01X342151D02*
X338950D01*
G02X338951Y832311I1J2010D01*
G01X342151D01*
G02Y828291I0J-2010D01*
G37*
G36*
G01X329553D02*
X326352D01*
G02X326353Y832311I1J2010D01*
G01X329553D01*
G02Y828291I0J-2010D01*
G37*
G36*
G01X316954D02*
X313753D01*
G02X313754Y832311I1J2010D01*
G01X316954D01*
G02Y828291I0J-2010D01*
G37*
G36*
G01X279159D02*
X275958D01*
G02X275959Y832311I1J2010D01*
G01X279159D01*
G02Y828291I0J-2010D01*
G37*
G36*
G01X266561D02*
X263360D01*
G02X263361Y832311I1J2010D01*
G01X266561D01*
G02Y828291I0J-2010D01*
G37*
G36*
G01X253962D02*
X250761D01*
G02X250762Y832311I1J2010D01*
G01X253962D01*
G02Y828291I0J-2010D01*
G37*
G36*
G01X231915D02*
X228714D01*
G02X228715Y832311I1J2010D01*
G01X231915D01*
G02Y828291I0J-2010D01*
G37*
G36*
G01X219317D02*
X216117D01*
G02Y832311I0J2010D01*
G01X219318D01*
G02X219317Y828291I-1J-2010D01*
G37*
G36*
G01X206718D02*
X203517D01*
G02X203518Y832311I1J2010D01*
G01X206718D01*
G02Y828291I0J-2010D01*
G37*
G36*
G01X194120D02*
X190919D01*
G02X190920Y832311I1J2010D01*
G01X194120D01*
G02Y828291I0J-2010D01*
G37*
G36*
G01X200620Y819691D02*
X197419D01*
G02X197420Y823711I1J2010D01*
G01X200620D01*
G02Y819691I0J-2010D01*
G37*
G36*
G01X370875Y720990D02*
X367675D01*
G02Y725010I0J2010D01*
G01X370876D01*
G02X370875Y720990I-1J-2010D01*
G37*
G36*
G01X802200Y193990D02*
X798999D01*
G02X799000Y198010I1J2010D01*
G01X802200D01*
G02Y193990I0J-2010D01*
G37*
G36*
G01X1225348Y135950D02*
X1222148D01*
G02Y139970I0J2010D01*
G01X1225349D01*
G02X1225348Y135950I-1J-2010D01*
G37*
G36*
G01X1190835Y135889D02*
X1187635D01*
G02Y139909I0J2010D01*
G01X1190836D01*
G02X1190835Y135889I-1J-2010D01*
G37*
G36*
G01X1242900Y135841D02*
X1239700D01*
G02Y139861I0J2010D01*
G01X1242901D01*
G02X1242900Y135841I-1J-2010D01*
G37*
G36*
G01X1141900D02*
X1138700D01*
G02Y139861I0J2010D01*
G01X1141901D01*
G02X1141900Y135841I-1J-2010D01*
G37*
G36*
G01X718790Y114150D02*
Y117350D01*
G02X722810I2010J0D01*
G01Y114149D01*
G02X718790Y114150I-2010J1D01*
G37*
G36*
G01X568342Y92882D02*
X568235Y93048D01*
X568234Y93047D01*
X565281Y98559D01*
X565284Y98561D01*
X565213Y98720D01*
G02X569627Y100887I2245J1005D01*
G01X569721Y100710D01*
X569729Y100715D01*
X572588Y95380D01*
X572583Y95375D01*
X572642Y95249D01*
G02X568342Y92882I-2231J-1036D01*
G37*
G36*
G01X1170704D02*
X1170597Y93048D01*
X1170596Y93047D01*
X1167643Y98559D01*
X1167646Y98561D01*
X1167575Y98720D01*
G02X1171989Y100887I2245J1005D01*
G01X1172083Y100710D01*
X1172091Y100715D01*
X1174950Y95380D01*
X1174945Y95375D01*
X1175004Y95249D01*
G02X1170704Y92882I-2231J-1036D01*
G37*
G36*
G01X1222870D02*
X1222763Y93048D01*
X1222762Y93047D01*
X1219809Y98558D01*
X1219814Y98563D01*
X1219755Y98689D01*
G02X1224155Y100887I2231J1036D01*
G01X1224249Y100710D01*
X1224257Y100715D01*
X1227116Y95379D01*
X1227113Y95377D01*
X1227184Y95218D01*
G02X1222870Y92882I-2246J-1004D01*
G37*
G36*
G01X1188421D02*
X1188314Y93048D01*
X1188313Y93047D01*
X1185360Y98558D01*
X1185365Y98563D01*
X1185306Y98689D01*
G02X1189706Y100887I2231J1036D01*
G01X1189800Y100710D01*
X1189808Y100715D01*
X1192667Y95379D01*
X1192664Y95377D01*
X1192735Y95218D01*
G02X1188421Y92882I-2246J-1004D01*
G37*
G36*
G01X672673D02*
X672566Y93048D01*
X672565Y93047D01*
X669612Y98558D01*
X669617Y98563D01*
X669558Y98689D01*
G02X673958Y100887I2231J1036D01*
G01X674052Y100710D01*
X674060Y100715D01*
X676919Y95379D01*
X676916Y95377D01*
X676987Y95218D01*
G02X672673Y92882I-2246J-1004D01*
G37*
G36*
G01X663815D02*
X663708Y93048D01*
X663707Y93047D01*
X660754Y98558D01*
X660759Y98563D01*
X660700Y98689D01*
G02X665100Y100887I2231J1036D01*
G01X665194Y100710D01*
X665202Y100715D01*
X668061Y95379D01*
X668058Y95377D01*
X668129Y95218D01*
G02X663815Y92882I-2246J-1004D01*
G37*
G36*
G01X629366D02*
X629259Y93048D01*
X629258Y93047D01*
X626305Y98558D01*
X626310Y98563D01*
X626251Y98689D01*
G02X630651Y100887I2231J1036D01*
G01X630745Y100710D01*
X630753Y100715D01*
X633612Y95379D01*
X633609Y95377D01*
X633680Y95218D01*
G02X629366Y92882I-2246J-1004D01*
G37*
G36*
G01X620508D02*
X620401Y93048D01*
X620400Y93047D01*
X617447Y98558D01*
X617452Y98563D01*
X617393Y98689D01*
G02X621793Y100887I2231J1036D01*
G01X621887Y100710D01*
X621895Y100715D01*
X624754Y95379D01*
X624751Y95377D01*
X624822Y95218D01*
G02X620508Y92882I-2246J-1004D01*
G37*
G36*
G01X586059D02*
X585952Y93048D01*
X585951Y93047D01*
X582998Y98558D01*
X583003Y98563D01*
X582944Y98689D01*
G02X587344Y100887I2231J1036D01*
G01X587438Y100710D01*
X587446Y100715D01*
X590305Y95379D01*
X590302Y95377D01*
X590373Y95218D01*
G02X586059Y92882I-2246J-1004D01*
G37*
G36*
G01X542752D02*
X542645Y93048D01*
X542644Y93047D01*
X539691Y98558D01*
X539696Y98563D01*
X539637Y98689D01*
G02X544037Y100887I2231J1036D01*
G01X544131Y100710D01*
X544139Y100715D01*
X546998Y95379D01*
X546995Y95377D01*
X547066Y95218D01*
G02X542752Y92882I-2246J-1004D01*
G37*
G36*
G01X533793Y93052D02*
X530857Y98534D01*
X530856Y98535D01*
G02X535179Y100886I2154J1190D01*
G01X538131Y95374D01*
G02X533793Y93052I-2169J-1161D01*
G37*
G36*
G01X525035Y92882D02*
X524928Y93048D01*
X524927Y93047D01*
X521974Y98558D01*
X521979Y98563D01*
X521920Y98689D01*
G02X526320Y100887I2231J1036D01*
G01X526414Y100710D01*
X526422Y100715D01*
X529281Y95379D01*
X529278Y95377D01*
X529349Y95218D01*
G02X525035Y92882I-2246J-1004D01*
G37*
G36*
G01X1257218Y93052D02*
X1254266Y98564D01*
G02X1256412Y102185I2169J1161D01*
G02X1258604Y100886I23J-2460D01*
G01X1261540Y95404D01*
X1261541Y95403D01*
G02X1257218Y93052I-2154J-1190D01*
G37*
G36*
G01X1213911D02*
X1210959Y98564D01*
G02X1215297Y100886I2169J1161D01*
G01X1218233Y95404D01*
X1218234Y95403D01*
G02X1213911Y93052I-2154J-1190D01*
G37*
G36*
G01X654856D02*
X651904Y98564D01*
G02X656242Y100886I2169J1161D01*
G01X659178Y95404D01*
X659179Y95403D01*
G02X654856Y93052I-2154J-1190D01*
G37*
G36*
G01X611549D02*
X608597Y98564D01*
G02X612935Y100886I2169J1161D01*
G01X615871Y95404D01*
X615872Y95403D01*
G02X611549Y93052I-2154J-1190D01*
G37*
G36*
G01X718790Y93150D02*
Y96351D01*
G02X722810Y96350I2010J-1D01*
G01Y93150D01*
G02X718790I-2010J0D01*
G37*
G36*
G01X672673Y77921D02*
X672566Y78087D01*
X672565Y78086D01*
X669612Y83598D01*
X669615Y83600D01*
X669544Y83759D01*
G02X673958Y85926I2245J1005D01*
G01X674052Y85749D01*
X674060Y85754D01*
X676919Y80419D01*
X676914Y80414D01*
X676973Y80288D01*
G02X672673Y77921I-2231J-1036D01*
G37*
G36*
G01X663815D02*
X663708Y78087D01*
X663707Y78086D01*
X660754Y83598D01*
X660757Y83600D01*
X660686Y83759D01*
G02X665100Y85926I2245J1005D01*
G01X665194Y85749D01*
X665202Y85754D01*
X668061Y80419D01*
X668056Y80414D01*
X668115Y80288D01*
G02X663815Y77921I-2231J-1036D01*
G37*
G36*
G01X586059D02*
X585952Y78087D01*
X585951Y78086D01*
X582998Y83598D01*
X583001Y83600D01*
X582930Y83759D01*
G02X587344Y85926I2245J1005D01*
G01X587438Y85749D01*
X587446Y85754D01*
X590305Y80419D01*
X590300Y80414D01*
X590359Y80288D01*
G02X586059Y77921I-2231J-1036D01*
G37*
G36*
G01X1188421D02*
X1188314Y78087D01*
X1188313Y78086D01*
X1185360Y83598D01*
X1185363Y83600D01*
X1185292Y83759D01*
G02X1189706Y85926I2245J1005D01*
G01X1189800Y85749D01*
X1189808Y85754D01*
X1192667Y80419D01*
X1192662Y80414D01*
X1192721Y80288D01*
G02X1188421Y77921I-2231J-1036D01*
G37*
G36*
G01X1145114D02*
X1145007Y78087D01*
X1145006Y78086D01*
X1142053Y83597D01*
X1142058Y83602D01*
X1141999Y83728D01*
G02X1146399Y85926I2231J1036D01*
G01X1146493Y85749D01*
X1146501Y85754D01*
X1149360Y80418D01*
X1149357Y80416D01*
X1149428Y80257D01*
G02X1145114Y77921I-2246J-1004D01*
G37*
G36*
G01X533793Y78091D02*
X530857Y83573D01*
X530856Y83574D01*
G02X535179Y85925I2154J1190D01*
G01X538131Y80413D01*
G02X533793Y78091I-2169J-1161D01*
G37*
G36*
G01X1179462D02*
X1176510Y83603D01*
G02X1180848Y85925I2169J1161D01*
G01X1183784Y80443D01*
X1183785Y80442D01*
G02X1179462Y78091I-2154J-1190D01*
G37*
G36*
G01X1101339Y70669D02*
X1101290Y73869D01*
G02X1105310Y73931I2010J31D01*
G01X1105359Y70732D01*
G02X1101339Y70669I-2010J-32D01*
G37*
G36*
G01X715830Y47890D02*
X714430D01*
G02X713920Y48400I0J510D01*
G01Y53900D01*
G02X714430Y54410I510J0D01*
G01X719230D01*
G02X719740Y53900I0J-510D01*
G01Y48400D01*
G02X719230Y47890I-510J0D01*
G01X717830D01*
G02X717770Y47894I4J510D01*
G01X717758Y47895D01*
X715902D01*
X715890Y47894D01*
G02X715830Y47890I-64J506D01*
G37*
G36*
G01X1170704Y48000D02*
X1170597Y48166D01*
X1170596Y48165D01*
X1167643Y53676D01*
X1167648Y53681D01*
X1167589Y53807D01*
G02X1171989Y56005I2231J1036D01*
G01X1172083Y55828D01*
X1172091Y55833D01*
X1174950Y50497D01*
X1174947Y50495D01*
X1175018Y50336D01*
G02X1170704Y48000I-2246J-1004D01*
G37*
G36*
G01X568342D02*
X568235Y48166D01*
X568234Y48165D01*
X565281Y53676D01*
X565286Y53681D01*
X565227Y53807D01*
G02X569627Y56005I2231J1036D01*
G01X569721Y55828D01*
X569729Y55833D01*
X572588Y50497D01*
X572585Y50495D01*
X572656Y50336D01*
G02X568342Y48000I-2246J-1004D01*
G37*
G36*
G01X716090Y24380D02*
X714690D01*
G02X714280Y24790I0J410D01*
G01Y26190D01*
G02X714283Y26239I410J-1D01*
G01X714284Y26250D01*
Y28922D01*
X714283Y28933D01*
G02X714280Y28980I407J50D01*
G01Y30380D01*
G02X714690Y30790I410J0D01*
G01X717941D01*
X717966Y30797D01*
G02X718070Y30810I102J-397D01*
G01X719470D01*
G02X719880Y30400I0J-410D01*
G01Y26319D01*
X719887Y26294D01*
G02X719900Y26190I-397J-102D01*
G01Y24790D01*
G02X719490Y24380I-410J0D01*
G01X718090D01*
G02X718057Y24381I-4J410D01*
G01X718049Y24382D01*
X716130D01*
X716122Y24381D01*
G02X716090Y24380I-29J409D01*
G37*
G36*
G01X1292817Y139490D02*
X1296018D01*
G02X1296017Y135466I-1J-2012D01*
G01X1292817D01*
G02Y139490I0J2012D01*
G37*
G36*
G01X1283343Y143592D02*
X1286544D01*
G02X1286543Y139570I-1J-2011D01*
G01X1283343D01*
G02Y143592I0J2011D01*
G37*
G36*
G01X1261944Y143758D02*
X1258743D01*
G02X1258744Y147782I1J2012D01*
G01X1261944D01*
G02Y143758I0J-2012D01*
G37*
G36*
G01X1277265Y135662D02*
X1274064D01*
G02X1274065Y139684I1J2011D01*
G01X1277265D01*
G02Y135662I0J-2011D01*
G37*
G36*
G01X1266177Y92880D02*
X1266070Y93046D01*
X1266068Y93045D01*
X1263114Y98558D01*
X1263119Y98563D01*
X1263060Y98690D01*
G02X1267463Y100888I2233J1035D01*
G01X1267557Y100712D01*
X1267565Y100716D01*
X1270425Y95378D01*
X1270422Y95377D01*
X1270493Y95218D01*
G02X1266177Y92880I-2248J-1004D01*
G37*
G36*
G01Y77919D02*
X1266070Y78085D01*
X1266068Y78084D01*
X1263114Y83599D01*
X1263117Y83600D01*
X1263046Y83759D01*
G02X1267463Y85927I2247J1006D01*
G01X1267557Y85751D01*
X1267565Y85755D01*
X1270425Y80419D01*
X1270420Y80414D01*
X1270479Y80287D01*
G02X1266177Y77919I-2234J-1034D01*
G37*
G36*
G01X1275035D02*
X1274928Y78085D01*
X1274926Y78084D01*
X1271972Y83599D01*
X1271975Y83600D01*
X1271904Y83759D01*
G02X1276321Y85927I2247J1006D01*
G01X1276415Y85751D01*
X1276423Y85755D01*
X1279283Y80419D01*
X1279278Y80414D01*
X1279337Y80287D01*
G02X1275035Y77919I-2234J-1034D01*
G37*
G36*
G01Y92880D02*
X1274928Y93046D01*
X1274926Y93045D01*
X1271972Y98558D01*
X1271977Y98563D01*
X1271918Y98690D01*
G02X1276321Y100888I2233J1035D01*
G01X1276415Y100712D01*
X1276423Y100716D01*
X1279283Y95378D01*
X1279280Y95377D01*
X1279351Y95218D01*
G02X1275035Y92880I-2248J-1004D01*
G37*
G36*
G01X1258605Y56005D02*
X1261557Y50493D01*
G02X1257217Y48169I-2170J-1162D01*
G01X1254281Y53651D01*
X1254280Y53652D01*
G02X1258605Y56005I2155J1191D01*
G37*
G36*
G01X1275035Y47998D02*
X1274928Y48164D01*
X1274926Y48163D01*
X1271972Y53676D01*
X1271977Y53681D01*
X1271918Y53808D01*
G02X1276321Y56006I2233J1035D01*
G01X1276415Y55830D01*
X1276423Y55834D01*
X1279283Y50496D01*
X1279280Y50495D01*
X1279351Y50336D01*
G02X1275035Y47998I-2248J-1004D01*
G37*
G36*
G01X1266177D02*
X1266070Y48164D01*
X1266068Y48163D01*
X1263114Y53676D01*
X1263119Y53681D01*
X1263060Y53808D01*
G02X1267463Y56006I2233J1035D01*
G01X1267557Y55830D01*
X1267565Y55834D01*
X1270425Y50496D01*
X1270422Y50495D01*
X1270493Y50336D01*
G02X1266177Y47998I-2248J-1004D01*
G37*
G36*
G01X1275030Y62966D02*
X1274929Y63124D01*
X1274926Y63123D01*
X1271972Y68636D01*
X1271977Y68641D01*
X1271918Y68768D01*
G02X1276320Y70967I2233J1035D01*
G01X1276414Y70791D01*
X1276423Y70796D01*
X1279283Y65458D01*
X1279280Y65457D01*
X1279354Y65290D01*
G02X1275030Y62966I-2250J-999D01*
G37*
G36*
G01X1266172D02*
X1266071Y63124D01*
X1266068Y63123D01*
X1263114Y68636D01*
X1263119Y68641D01*
X1263060Y68768D01*
G02X1267462Y70967I2233J1035D01*
G01X1267556Y70791D01*
X1267565Y70796D01*
X1270425Y65458D01*
X1270422Y65457D01*
X1270496Y65290D01*
G02X1266172Y62966I-2250J-999D01*
G37*
G36*
G01X1234209Y140452D02*
X1231008D01*
G02X1231009Y144474I1J2011D01*
G01X1234209D01*
G02Y140452I0J-2011D01*
G37*
G36*
G01X1222870Y77919D02*
X1222763Y78085D01*
X1222761Y78084D01*
X1219807Y83599D01*
X1219810Y83600D01*
X1219739Y83759D01*
G02X1224156Y85927I2247J1006D01*
G01X1224250Y85751D01*
X1224258Y85755D01*
X1227118Y80419D01*
X1227113Y80414D01*
X1227172Y80287D01*
G02X1222870Y77919I-2234J-1034D01*
G37*
G36*
G01X1231728Y92880D02*
X1231621Y93046D01*
X1231619Y93045D01*
X1228665Y98558D01*
X1228670Y98563D01*
X1228611Y98690D01*
G02X1233014Y100888I2233J1035D01*
G01X1233108Y100712D01*
X1233116Y100716D01*
X1235976Y95378D01*
X1235973Y95377D01*
X1236044Y95218D01*
G02X1231728Y92880I-2248J-1004D01*
G37*
G36*
G01Y77919D02*
X1231621Y78085D01*
X1231619Y78084D01*
X1228665Y83599D01*
X1228668Y83600D01*
X1228597Y83759D01*
G02X1233014Y85927I2247J1006D01*
G01X1233108Y85751D01*
X1233116Y85755D01*
X1235976Y80419D01*
X1235971Y80414D01*
X1236030Y80287D01*
G02X1231728Y77919I-2234J-1034D01*
G37*
G36*
G01Y47998D02*
X1231621Y48164D01*
X1231619Y48163D01*
X1228665Y53676D01*
X1228670Y53681D01*
X1228611Y53808D01*
G02X1233014Y56006I2233J1035D01*
G01X1233108Y55830D01*
X1233116Y55834D01*
X1235976Y50496D01*
X1235973Y50495D01*
X1236044Y50336D01*
G02X1231728Y47998I-2248J-1004D01*
G37*
G36*
G01X1222870D02*
X1222763Y48164D01*
X1222761Y48163D01*
X1219807Y53676D01*
X1219812Y53681D01*
X1219753Y53808D01*
G02X1224156Y56006I2233J1035D01*
G01X1224250Y55830D01*
X1224258Y55834D01*
X1227118Y50496D01*
X1227115Y50495D01*
X1227186Y50336D01*
G02X1222870Y47998I-2248J-1004D01*
G37*
G36*
G01X1231723Y62966D02*
X1231622Y63124D01*
X1231619Y63123D01*
X1228665Y68636D01*
X1228670Y68641D01*
X1228611Y68768D01*
G02X1233013Y70967I2233J1035D01*
G01X1233107Y70791D01*
X1233116Y70796D01*
X1235976Y65458D01*
X1235973Y65457D01*
X1236047Y65290D01*
G02X1231723Y62966I-2250J-999D01*
G37*
G36*
G01X1222865D02*
X1222764Y63124D01*
X1222761Y63123D01*
X1219807Y68636D01*
X1219812Y68641D01*
X1219753Y68768D01*
G02X1224155Y70967I2233J1035D01*
G01X1224249Y70791D01*
X1224258Y70796D01*
X1227118Y65458D01*
X1227115Y65457D01*
X1227189Y65290D01*
G02X1222865Y62966I-2250J-999D01*
G37*
G36*
G01X1203791Y158742D02*
X1206992D01*
G02X1206991Y154718I-1J-2012D01*
G01X1203791D01*
G02Y158742I0J2012D01*
G37*
G36*
G01X1196200Y144862D02*
X1199401D01*
G02X1199400Y140840I-1J-2011D01*
G01X1196200D01*
G02Y144862I0J2011D01*
G37*
G36*
G01X1215298Y56005D02*
X1218250Y50493D01*
G02X1213910Y48169I-2170J-1162D01*
G01X1210974Y53651D01*
X1210973Y53652D01*
G02X1215298Y56005I2155J1191D01*
G37*
G36*
G01X1188421Y47998D02*
X1188314Y48164D01*
X1188312Y48163D01*
X1185358Y53676D01*
X1185363Y53681D01*
X1185304Y53808D01*
G02X1189707Y56006I2233J1035D01*
G01X1189801Y55830D01*
X1189809Y55834D01*
X1192669Y50496D01*
X1192666Y50495D01*
X1192737Y50336D01*
G02X1188421Y47998I-2248J-1004D01*
G37*
G36*
G01X1188416Y62966D02*
X1188315Y63124D01*
X1188312Y63123D01*
X1185358Y68636D01*
X1185363Y68641D01*
X1185304Y68768D01*
G02X1189706Y70967I2233J1035D01*
G01X1189800Y70791D01*
X1189809Y70796D01*
X1192669Y65458D01*
X1192666Y65457D01*
X1192740Y65290D01*
G02X1188416Y62966I-2250J-999D01*
G37*
G36*
G01X1182061Y140466D02*
X1178860D01*
G02X1178861Y144490I1J2012D01*
G01X1182061D01*
G02Y140466I0J-2012D01*
G37*
G36*
G01X1161307Y136494D02*
X1158106D01*
G02X1158107Y140516I1J2011D01*
G01X1161307D01*
G02Y136494I0J-2011D01*
G37*
G36*
G01X1180849Y100887D02*
X1183801Y95375D01*
G02X1179461Y93051I-2170J-1162D01*
G01X1176525Y98533D01*
X1176524Y98534D01*
G02X1180849Y100887I2155J1191D01*
G37*
G36*
G01Y56005D02*
X1183801Y50493D01*
G02X1179461Y48169I-2170J-1162D01*
G01X1176525Y53651D01*
X1176524Y53652D01*
G02X1180849Y56005I2155J1191D01*
G37*
G36*
G01X1179562Y62959D02*
X1179455Y63125D01*
X1179453Y63124D01*
X1176500Y68636D01*
X1176505Y68641D01*
X1176446Y68768D01*
G02X1180849Y70966I2233J1035D01*
G01X1180943Y70790D01*
X1180951Y70794D01*
X1183810Y65457D01*
X1183807Y65456D01*
X1183878Y65297D01*
G02X1179562Y62959I-2248J-1004D01*
G37*
G36*
G01X1119990Y130124D02*
Y133325D01*
G02X1124012Y133324I2011J-1D01*
G01Y130124D01*
G02X1119990I-2011J0D01*
G37*
G36*
G01X1127397Y92880D02*
X1127290Y93046D01*
X1127288Y93045D01*
X1124334Y98558D01*
X1124339Y98563D01*
X1124280Y98690D01*
G02X1128683Y100888I2233J1035D01*
G01X1128777Y100712D01*
X1128785Y100716D01*
X1131645Y95378D01*
X1131642Y95377D01*
X1131713Y95218D01*
G02X1127397Y92880I-2248J-1004D01*
G37*
G36*
G01X1137542Y100887D02*
X1140494Y95375D01*
G02X1136154Y93051I-2170J-1162D01*
G01X1133218Y98533D01*
X1133217Y98534D01*
G02X1137542Y100887I2155J1191D01*
G37*
G36*
G01X1111088Y81902D02*
X1111198Y82050D01*
X1111197Y82052D01*
X1113341Y84432D01*
X1113343Y84430D01*
X1113475Y84553D01*
G02X1116337Y81733I1367J-1475D01*
G01X1116203Y81585D01*
X1116211Y81578D01*
X1114203Y79348D01*
X1114192D01*
X1114133Y79288D01*
G02X1111088Y81902I-1432J1412D01*
G37*
G36*
G01X1145114Y92880D02*
X1145007Y93046D01*
X1145005Y93045D01*
X1142051Y98558D01*
X1142056Y98563D01*
X1141997Y98690D01*
G02X1146400Y100888I2233J1035D01*
G01X1146494Y100712D01*
X1146502Y100716D01*
X1149362Y95378D01*
X1149359Y95377D01*
X1149430Y95218D01*
G02X1145114Y92880I-2248J-1004D01*
G37*
G36*
G01X1137542Y85926D02*
X1140494Y80414D01*
G02X1136154Y78090I-2170J-1162D01*
G01X1133218Y83572D01*
X1133217Y83573D01*
G02X1137542Y85926I2155J1191D01*
G37*
G36*
G01X1127397Y47998D02*
X1127290Y48164D01*
X1127288Y48163D01*
X1124334Y53678D01*
X1124337Y53679D01*
X1124266Y53838D01*
G02X1128683Y56006I2247J1006D01*
G01X1128777Y55830D01*
X1128785Y55834D01*
X1131645Y50498D01*
X1131640Y50493D01*
X1131699Y50366D01*
G02X1127397Y47998I-2234J-1034D01*
G37*
G36*
G01X1145114D02*
X1145007Y48164D01*
X1145005Y48163D01*
X1142051Y53678D01*
X1142054Y53679D01*
X1141983Y53838D01*
G02X1146400Y56006I2247J1006D01*
G01X1146494Y55830D01*
X1146502Y55834D01*
X1149362Y50498D01*
X1149357Y50493D01*
X1149416Y50366D01*
G02X1145114Y47998I-2234J-1034D01*
G37*
G36*
G01X1137542Y56005D02*
X1140478Y50523D01*
X1140479Y50522D01*
G02X1136154Y48169I-2155J-1191D01*
G01X1133202Y53681D01*
G02X1137542Y56005I2170J1162D01*
G37*
G36*
G01X1145109Y62966D02*
X1145008Y63124D01*
X1145005Y63123D01*
X1142051Y68636D01*
X1142056Y68641D01*
X1141997Y68768D01*
G02X1146399Y70967I2233J1035D01*
G01X1146493Y70791D01*
X1146502Y70796D01*
X1149362Y65458D01*
X1149359Y65457D01*
X1149433Y65290D01*
G02X1145109Y62966I-2250J-999D01*
G37*
G36*
G01X1136255Y62959D02*
X1136148Y63125D01*
X1136146Y63124D01*
X1133193Y68636D01*
X1133198Y68641D01*
X1133139Y68768D01*
G02X1137542Y70966I2233J1035D01*
G01X1137636Y70790D01*
X1137644Y70794D01*
X1140503Y65457D01*
X1140500Y65456D01*
X1140571Y65297D01*
G02X1136255Y62959I-2248J-1004D01*
G37*
G36*
G01X1069124Y57175D02*
Y60376D01*
G02X1073146Y60375I2011J-1D01*
G01Y57175D01*
G02X1069124I-2011J0D01*
G37*
G36*
G01X1059012Y57700D02*
Y54499D01*
G02X1054988Y54500I-2012J1D01*
G01Y57700D01*
G02X1059012I2012J0D01*
G37*
G36*
G01X1063212Y24088D02*
Y20887D01*
G02X1059188Y20888I-2012J1D01*
G01Y24088D01*
G02X1063212I2012J0D01*
G37*
G36*
G01X1067712Y36088D02*
Y32887D01*
G02X1063688Y32888I-2012J1D01*
G01Y36088D01*
G02X1067712I2012J0D01*
G37*
G36*
G01X1064198Y19800D02*
Y25200D01*
G02X1064600Y25602I402J0D01*
G01X1069400D01*
G02X1069802Y25200I0J-402D01*
G01Y19800D01*
G02X1069400Y19398I-402J0D01*
G01X1064600D01*
G02X1064198Y19800I0J402D01*
G37*
G36*
G01X1068698Y31800D02*
Y37200D01*
G02X1069100Y37602I402J0D01*
G01X1073900D01*
G02X1074302Y37200I0J-402D01*
G01Y31800D01*
G02X1073900Y31398I-402J0D01*
G01X1069100D01*
G02X1068698Y31800I0J402D01*
G37*
G36*
G01X828698Y175400D02*
Y180500D01*
G02X829200Y181002I502J0D01*
G01X834400D01*
G02X834902Y180500I0J-502D01*
G01Y175400D01*
G02X834400Y174898I-502J0D01*
G01X829200D01*
G02X828698Y175400I0J502D01*
G37*
G36*
G01X781218Y183890D02*
Y179489D01*
G02X776396Y179490I-2411J1D01*
G01Y183890D01*
G02X781218I2411J0D01*
G37*
G36*
G01X787614Y198215D02*
X792013Y198189D01*
G02X791986Y193367I-14J-2411D01*
G01X787586Y193393D01*
G02X787614Y198215I14J2411D01*
G37*
G36*
G01X790348Y176043D02*
Y180444D01*
G02X795172Y180443I2412J-1D01*
G01Y176043D01*
G02X790348I-2412J0D01*
G37*
G36*
G01X722812Y81350D02*
Y78149D01*
G02X718788Y78150I-2012J1D01*
G01Y81350D01*
G02X722812I2012J0D01*
G37*
G36*
G01X734512Y101621D02*
Y98420D01*
G02X730488Y98421I-2012J1D01*
G01Y101621D01*
G02X734512I2012J0D01*
G37*
G36*
G01X722812Y105350D02*
Y102149D01*
G02X718788Y102150I-2012J1D01*
G01Y105350D01*
G02X722812I2012J0D01*
G37*
G36*
G01X728620Y49251D02*
Y46050D01*
G02X724598Y46051I-2011J1D01*
G01Y49251D01*
G02X728620I2011J0D01*
G37*
G36*
G01X722955Y35106D02*
X726156D01*
G02X726155Y31084I-1J-2011D01*
G01X722955D01*
G02Y35106I0J2011D01*
G37*
G36*
G01X683600Y376706D02*
X680099D01*
G02X680100Y380730I1J2012D01*
G01X683600D01*
G02Y376706I0J-2012D01*
G37*
G36*
G01X662256Y352200D02*
Y348999D01*
G02X658232Y349000I-2012J1D01*
G01Y352200D01*
G02X662256I2012J0D01*
G37*
G36*
G01X640550Y323512D02*
X643751D01*
G02X643750Y319488I-1J-2012D01*
G01X640550D01*
G02Y323512I0J2012D01*
G37*
G36*
G01X656243Y56005D02*
X659195Y50493D01*
G02X654855Y48169I-2170J-1162D01*
G01X651919Y53651D01*
X651918Y53652D01*
G02X656243Y56005I2155J1191D01*
G37*
G36*
G01X663815Y47998D02*
X663708Y48164D01*
X663706Y48163D01*
X660752Y53676D01*
X660757Y53681D01*
X660698Y53808D01*
G02X665101Y56006I2233J1035D01*
G01X665195Y55830D01*
X665203Y55834D01*
X668063Y50496D01*
X668060Y50495D01*
X668131Y50336D01*
G02X663815Y47998I-2248J-1004D01*
G37*
G36*
G01X663810Y62966D02*
X663709Y63124D01*
X663706Y63123D01*
X660752Y68636D01*
X660757Y68641D01*
X660698Y68768D01*
G02X665100Y70967I2233J1035D01*
G01X665194Y70791D01*
X665203Y70796D01*
X668063Y65458D01*
X668060Y65457D01*
X668134Y65290D01*
G02X663810Y62966I-2250J-999D01*
G37*
G36*
G01X672668D02*
X672567Y63124D01*
X672564Y63123D01*
X669610Y68636D01*
X669615Y68641D01*
X669556Y68768D01*
G02X673958Y70967I2233J1035D01*
G01X674052Y70791D01*
X674061Y70796D01*
X676921Y65458D01*
X676918Y65457D01*
X676992Y65290D01*
G02X672668Y62966I-2250J-999D01*
G37*
G36*
G01X672673Y47998D02*
X672566Y48164D01*
X672564Y48163D01*
X669610Y53676D01*
X669615Y53681D01*
X669556Y53808D01*
G02X673959Y56006I2233J1035D01*
G01X674053Y55830D01*
X674061Y55834D01*
X676921Y50496D01*
X676918Y50495D01*
X676989Y50336D01*
G02X672673Y47998I-2248J-1004D01*
G37*
G36*
G01X636950Y151662D02*
X640151D01*
G02X640150Y147638I-1J-2012D01*
G01X636950D01*
G02Y151662I0J2012D01*
G37*
G36*
G01X638150Y135868D02*
X634949D01*
G02X634950Y139892I1J2012D01*
G01X638150D01*
G02Y135868I0J-2012D01*
G37*
G36*
G01X627826D02*
X624625D01*
G02X624626Y139892I1J2012D01*
G01X627826D01*
G02Y135868I0J-2012D01*
G37*
G36*
G01X629366Y77919D02*
X629259Y78085D01*
X629257Y78084D01*
X626303Y83599D01*
X626306Y83600D01*
X626235Y83759D01*
G02X630652Y85927I2247J1006D01*
G01X630746Y85751D01*
X630754Y85755D01*
X633614Y80419D01*
X633609Y80414D01*
X633668Y80287D01*
G02X629366Y77919I-2234J-1034D01*
G37*
G36*
G01X612936Y56005D02*
X615888Y50493D01*
G02X611548Y48169I-2170J-1162D01*
G01X608612Y53651D01*
X608611Y53652D01*
G02X612936Y56005I2155J1191D01*
G37*
G36*
G01X629361Y62966D02*
X629260Y63124D01*
X629257Y63123D01*
X626303Y68636D01*
X626308Y68641D01*
X626249Y68768D01*
G02X630651Y70967I2233J1035D01*
G01X630745Y70791D01*
X630754Y70796D01*
X633614Y65458D01*
X633611Y65457D01*
X633685Y65290D01*
G02X629361Y62966I-2250J-999D01*
G37*
G36*
G01X620503D02*
X620402Y63124D01*
X620399Y63123D01*
X617445Y68636D01*
X617450Y68641D01*
X617391Y68768D01*
G02X621793Y70967I2233J1035D01*
G01X621887Y70791D01*
X621896Y70796D01*
X624756Y65458D01*
X624753Y65457D01*
X624827Y65290D01*
G02X620503Y62966I-2250J-999D01*
G37*
G36*
G01X620508Y47998D02*
X620401Y48164D01*
X620399Y48163D01*
X617445Y53676D01*
X617450Y53681D01*
X617391Y53808D01*
G02X621794Y56006I2233J1035D01*
G01X621888Y55830D01*
X621896Y55834D01*
X624756Y50496D01*
X624753Y50495D01*
X624824Y50336D01*
G02X620508Y47998I-2248J-1004D01*
G37*
G36*
G01X629366D02*
X629259Y48164D01*
X629257Y48163D01*
X626303Y53676D01*
X626308Y53681D01*
X626249Y53808D01*
G02X630652Y56006I2233J1035D01*
G01X630746Y55830D01*
X630754Y55834D01*
X633614Y50496D01*
X633611Y50495D01*
X633682Y50336D01*
G02X629366Y47998I-2248J-1004D01*
G37*
G36*
G01X594150Y151962D02*
X597351D01*
G02X597350Y147938I-1J-2012D01*
G01X594150D01*
G02Y151962I0J2012D01*
G37*
G36*
G01X601250Y139792D02*
X604451D01*
G02X604450Y135768I-1J-2012D01*
G01X601250D01*
G02Y139792I0J2012D01*
G37*
G36*
G01X584650Y139812D02*
X587851D01*
G02X587850Y135788I-1J-2012D01*
G01X584650D01*
G02Y139812I0J2012D01*
G37*
G36*
G01X577650Y135768D02*
X574449D01*
G02X574450Y139792I1J2012D01*
G01X577650D01*
G02Y135768I0J-2012D01*
G37*
G36*
G01X578487Y85926D02*
X581423Y80444D01*
X581424Y80443D01*
G02X577099Y78090I-2155J-1191D01*
G01X574147Y83602D01*
G02X578487Y85926I2170J1162D01*
G37*
G36*
G01X577099Y93051D02*
X574163Y98533D01*
X574162Y98534D01*
G02X578487Y100887I2155J1191D01*
G01X581439Y95375D01*
G02X577099Y93051I-2170J-1162D01*
G37*
G36*
G01X577200Y62959D02*
X577093Y63125D01*
X577091Y63124D01*
X574138Y68636D01*
X574143Y68641D01*
X574084Y68768D01*
G02X578487Y70966I2233J1035D01*
G01X578581Y70790D01*
X578589Y70794D01*
X581448Y65457D01*
X581445Y65456D01*
X581516Y65297D01*
G02X577200Y62959I-2248J-1004D01*
G37*
G36*
G01X586059Y47998D02*
X585952Y48164D01*
X585950Y48163D01*
X582996Y53676D01*
X583001Y53681D01*
X582942Y53808D01*
G02X587345Y56006I2233J1035D01*
G01X587439Y55830D01*
X587447Y55834D01*
X590307Y50496D01*
X590304Y50495D01*
X590375Y50336D01*
G02X586059Y47998I-2248J-1004D01*
G37*
G36*
G01X578487Y56005D02*
X581439Y50493D01*
G02X577099Y48169I-2170J-1162D01*
G01X574163Y53651D01*
X574162Y53652D01*
G02X578487Y56005I2155J1191D01*
G37*
G36*
G01X586054Y62966D02*
X585953Y63124D01*
X585950Y63123D01*
X582996Y68636D01*
X583001Y68641D01*
X582942Y68768D01*
G02X587344Y70967I2233J1035D01*
G01X587438Y70791D01*
X587447Y70796D01*
X590307Y65458D01*
X590304Y65457D01*
X590378Y65290D01*
G02X586054Y62966I-2250J-999D01*
G37*
G36*
G01X548700Y150188D02*
X545499D01*
G02X545500Y154212I1J2012D01*
G01X548700D01*
G02Y150188I0J-2012D01*
G37*
G36*
G01X541600Y139780D02*
X544801D01*
G02X544800Y135758I-1J-2011D01*
G01X541600D01*
G02Y139780I0J2011D01*
G37*
G36*
G01X542752Y47998D02*
X542645Y48164D01*
X542643Y48163D01*
X539689Y53678D01*
X539692Y53679D01*
X539621Y53838D01*
G02X544038Y56006I2247J1006D01*
G01X544132Y55830D01*
X544140Y55834D01*
X547000Y50498D01*
X546995Y50493D01*
X547054Y50366D01*
G02X542752Y47998I-2234J-1034D01*
G37*
G36*
G01X542747Y62966D02*
X542646Y63124D01*
X542643Y63123D01*
X539689Y68636D01*
X539694Y68641D01*
X539635Y68768D01*
G02X544037Y70967I2233J1035D01*
G01X544131Y70791D01*
X544140Y70796D01*
X547000Y65458D01*
X546997Y65457D01*
X547071Y65290D01*
G02X542747Y62966I-2250J-999D01*
G37*
G36*
G01X521098Y168200D02*
Y163799D01*
G02X516274Y163800I-2412J1D01*
G01Y168200D01*
G02X521098I2412J0D01*
G37*
G36*
G01X526977Y142720D02*
X530178D01*
G02X530177Y138696I-1J-2012D01*
G01X526977D01*
G02Y142720I0J2012D01*
G37*
G36*
G01X519300Y136860D02*
X516099D01*
G02X516100Y140882I1J2011D01*
G01X519300D01*
G02Y136860I0J-2011D01*
G37*
G36*
G01X525035Y47998D02*
X524928Y48164D01*
X524926Y48163D01*
X521972Y53678D01*
X521975Y53679D01*
X521904Y53838D01*
G02X526321Y56006I2247J1006D01*
G01X526415Y55830D01*
X526423Y55834D01*
X529283Y50498D01*
X529278Y50493D01*
X529337Y50366D01*
G02X525035Y47998I-2234J-1034D01*
G37*
G36*
G01X535180Y56005D02*
X538116Y50523D01*
X538117Y50522D01*
G02X533792Y48169I-2155J-1191D01*
G01X530840Y53681D01*
G02X535180Y56005I2170J1162D01*
G37*
G36*
G01X533893Y62959D02*
X533786Y63125D01*
X533784Y63124D01*
X530831Y68636D01*
X530836Y68641D01*
X530777Y68768D01*
G02X535180Y70966I2233J1035D01*
G01X535274Y70790D01*
X535282Y70794D01*
X538141Y65457D01*
X538138Y65456D01*
X538209Y65297D01*
G02X533893Y62959I-2248J-1004D01*
G37*
G36*
G01X406452Y323300D02*
Y318899D01*
G02X401628Y318900I-2412J1D01*
G01Y323300D01*
G02X406452I2412J0D01*
G37*
G36*
G01X401588Y142542D02*
Y146043D01*
G02X405612Y146042I2012J-1D01*
G01Y142542D01*
G02X401588I-2012J0D01*
G37*
G36*
G01X403312Y156715D02*
Y153214D01*
G02X399288Y153215I-2012J1D01*
G01Y156715D01*
G02X403312I2012J0D01*
G37*
G36*
G01X360545Y730825D02*
X360662Y730965D01*
X360661Y730966D01*
X362924Y733230D01*
X362937D01*
X362995Y733283D01*
G02X365900Y730514I1360J-1482D01*
G01X365783Y730374D01*
X365784Y730373D01*
X363519Y728108D01*
X363518Y728109D01*
X363378Y727992D01*
G02X360545Y730825I-1287J1546D01*
G37*
G36*
G01X339640Y301534D02*
Y305035D01*
G02X343664Y305034I2012J-1D01*
G01Y301534D01*
G02X339640I-2012J0D01*
G37*
G36*
G01X370914Y40157D02*
G02X365945Y35188I-4969J0D01*
G01X356102D01*
G02X351132Y40157I0J4970D01*
G01Y71654D01*
G02X356102Y76624I4970J0D01*
G01X365945D01*
G02X370914Y71654I-1J-4970D01*
G01Y40157D01*
G37*
G36*
G01X260407Y500662D02*
X257206D01*
G02X257207Y504686I1J2012D01*
G01X260407D01*
G02Y500662I0J-2012D01*
G37*
G36*
G01X231750Y770688D02*
X228549D01*
G02X228550Y774712I1J2012D01*
G01X231750D01*
G02Y770688I0J-2012D01*
G37*
G36*
G01X223872Y339875D02*
Y335474D01*
G02X219048Y335475I-2412J1D01*
G01Y339875D01*
G02X223872I2412J0D01*
G37*
G36*
G01X209866Y186480D02*
X206296D01*
G02X206297Y190504I1J2012D01*
G01X209866D01*
G02Y186480I0J-2012D01*
G37*
G36*
G01X205376Y205902D02*
X210786D01*
G02X211188Y205500I0J-402D01*
G01Y200700D01*
G02X210786Y200298I-402J0D01*
G01X205376D01*
G02X204974Y200700I0J402D01*
G01Y205500D01*
G02X205376Y205902I402J0D01*
G37*
G36*
G01X105282Y565740D02*
Y561339D01*
G02X100458Y561340I-2412J1D01*
G01Y565740D01*
G02X105282I2412J0D01*
G37*
G36*
G01X93612Y453200D02*
Y448799D01*
G02X88788Y448800I-2412J1D01*
G01Y453200D01*
G02X93612I2412J0D01*
G37*
G36*
G01X93940Y438600D02*
Y443001D01*
G02X98762Y443000I2411J-1D01*
G01Y438600D01*
G02X93940I-2411J0D01*
G37*
G36*
G01X83500Y342188D02*
X80299D01*
G02X80300Y346212I1J2012D01*
G01X83500D01*
G02Y342188I0J-2012D01*
G37*
G36*
G01X77421Y320458D02*
X74220D01*
G02X74221Y324482I1J2012D01*
G01X77421D01*
G02Y320458I0J-2012D01*
G37*
G36*
G01X76325Y286220D02*
X73124D01*
G02X73125Y290242I1J2011D01*
G01X76325D01*
G02Y286220I0J-2011D01*
G37*
G36*
G01X74200Y218540D02*
X77401D01*
G02X77400Y214516I-1J-2012D01*
G01X74200D01*
G02Y218540I0J2012D01*
G37*
G36*
G01X92000Y208840D02*
X88799D01*
G02X88800Y212862I1J2011D01*
G01X92000D01*
G02Y208840I0J-2011D01*
G37*
G36*
G01X65400Y286244D02*
X62199D01*
G02X62200Y290268I1J2012D01*
G01X65400D01*
G02Y286244I0J-2012D01*
G37*
G36*
G01X65712Y263925D02*
Y260724D01*
G02X61688Y260725I-2012J1D01*
G01Y263925D01*
G02X65712I2012J0D01*
G37*
G36*
G01X57812Y269493D02*
Y266292D01*
G02X53788Y266293I-2012J1D01*
G01Y269493D01*
G02X57812I2012J0D01*
G37*
G36*
G01X56600Y209916D02*
X53399D01*
G02X53400Y213940I1J2012D01*
G01X56600D01*
G02Y209916I0J-2012D01*
G37*
G36*
G01X38050Y218740D02*
X41251D01*
G02X41250Y214716I-1J-2012D01*
G01X38050D01*
G02Y218740I0J2012D01*
G37*
G36*
G01X205300Y509788D02*
X200500D01*
G02X200144Y510004I0J401D01*
G02X200086Y510213I343J208D01*
G01Y515623D01*
G02X200487Y516024I401J0D01*
G01X205287D01*
G02X205643Y515809I0J-402D01*
G02X205702Y515600I-343J-210D01*
G01Y510190D01*
G02X205300Y509788I-402J0D01*
G37*
G36*
G01X1062220Y67328D02*
G02X1062046Y67288I-175J362D01*
G01X1057246D01*
G02X1056844Y67690I0J402D01*
G01Y73100D01*
G02X1057192Y73498I402J0D01*
G02X1057256Y73503I63J-395D01*
G01X1062056D01*
G02X1062456Y73103I0J-400D01*
G01Y67693D01*
G02X1062220Y67328I-400J0D01*
G37*
G54D53*
X1027722Y-9125D03*
X1054494D03*
G54D51*
X526215Y184000D03*
X565585D03*
G54D47*
X92990Y252362D03*
X116790D03*
X1301120Y173278D03*
Y183908D03*
G54D45*
X16200Y120100D03*
X27200Y821800D03*
X1384200Y122800D03*
X1373200Y823500D03*
G54D49*
X336417Y21260D03*
G54D46*
X42587Y151614D03*
X80579D03*
G54D48*
X293110Y55906D03*
G54D52*
X789850Y236220D03*
Y283464D03*
X1333661Y55905D03*
X1376968Y21259D03*
Y90551D03*
G54D50*
X336417D03*
G54D44*
X75800Y229289D03*
G54D43*
X90459Y223184D03*
X64600Y342700D03*
G54D19*
X54378Y237402D03*
G54D40*
X1075197Y92126D03*
Y112126D03*
G54D29*
X213900Y274372D03*
X1348785Y179358D03*
X1323195D03*
G54D14*
X27300Y229000D03*
X26600Y249217D03*
Y253582D03*
X24000Y308700D03*
X24639Y321239D03*
X25350Y389000D03*
X17500Y412374D03*
X20713Y410087D03*
X21300Y429500D03*
X20713Y418326D03*
X23720Y472640D03*
X29300Y539850D03*
X24800Y540900D03*
X26100Y671200D03*
X24000Y659000D03*
X29500Y676500D03*
X25200Y712650D03*
X17500Y706300D03*
X21300Y728400D03*
X21108Y732713D03*
X21250Y742650D03*
X27000Y754400D03*
X41250Y216728D03*
X53400Y211928D03*
X38050Y216728D03*
X56600Y211928D03*
X60872Y274328D03*
X63700Y260725D03*
X55800Y266293D03*
X63700Y263925D03*
X55800Y269493D03*
X44900Y261750D03*
X35300Y303100D03*
X47912Y294940D03*
X39000Y299500D03*
X53100Y279500D03*
X47800Y309400D03*
X31662Y303262D03*
X58700Y308600D03*
X61800Y306900D03*
X38800Y302900D03*
X62200Y288256D03*
X58383Y294947D03*
X47355Y303376D03*
X47991Y299958D03*
X49934Y280811D03*
X38500Y321400D03*
X58100Y334600D03*
X62400Y334500D03*
X31700Y314700D03*
X52050Y316100D03*
X51050Y321650D03*
X62400Y342700D03*
X38518Y376916D03*
X34153D03*
X39866Y371366D03*
X52521Y350357D03*
X54200Y347400D03*
X63500Y353960D03*
X62838Y392392D03*
X39300Y389557D03*
X35709Y426942D03*
X43500Y418802D03*
X47734Y465792D03*
X45531Y474400D03*
X64820Y455887D03*
X64680Y452389D03*
X64500Y459400D03*
X36750Y462900D03*
X53200Y462500D03*
X49812Y479921D03*
X33900Y469300D03*
X46500Y460300D03*
X46087Y455819D03*
X50140Y494559D03*
X60987Y489223D03*
X63519Y505320D03*
X62298Y484200D03*
X35700Y488500D03*
X60150Y506450D03*
X50140Y490750D03*
X60900Y495122D03*
X61870Y515670D03*
X60300Y533900D03*
X61128Y519646D03*
X61800Y537000D03*
X55950Y564500D03*
Y572500D03*
X63000Y558930D03*
X62611Y608289D03*
X62400Y624500D03*
X53000Y645000D03*
X63300Y634800D03*
X43600Y665700D03*
X54200Y666800D03*
X60700Y682100D03*
X47800Y666400D03*
X35766Y673178D03*
X34500Y666500D03*
X39900Y678100D03*
X33600Y675800D03*
X43100Y670900D03*
X36624Y669155D03*
X47300Y704400D03*
X42300Y704900D03*
X62000Y713000D03*
X45800Y685100D03*
X42100Y684000D03*
X63300Y697200D03*
X59100Y705600D03*
X42130Y694440D03*
X38000Y684000D03*
X59300Y734900D03*
X54300Y729900D03*
X49300Y734900D03*
X54300Y739900D03*
Y734900D03*
X56590Y720410D03*
X47800Y772900D03*
X35000Y769900D03*
X39000D03*
X42800Y770000D03*
X52500Y779600D03*
X64900Y780500D03*
X88259Y223184D03*
X92659D03*
X78000Y229289D03*
X73600D03*
X77400Y216528D03*
X88800Y210851D03*
X74200Y216528D03*
X92000Y210851D03*
X97480Y266420D03*
X77527Y255800D03*
X94530Y264671D03*
X75800Y274100D03*
X68100Y255000D03*
X89400Y279300D03*
X96798Y301484D03*
Y297915D03*
X95700Y293900D03*
X73125Y288231D03*
X76325D03*
X65400Y288256D03*
X84600Y303000D03*
X66800Y342700D03*
X83500Y344200D03*
X80300D03*
X77421Y322470D03*
X74221D03*
X79455Y357174D03*
X76055Y357145D03*
X82500Y362890D03*
X79267Y410185D03*
X80940Y395989D03*
X86904Y385798D03*
X72708Y382055D03*
X68365Y381464D03*
X84700Y396000D03*
X96351Y443000D03*
Y438600D03*
X85042Y439144D03*
X91200Y448800D03*
Y453200D03*
X89500Y466600D03*
X85748Y475813D03*
X73232Y476912D03*
X97100Y466500D03*
X98400Y454400D03*
X76100Y483400D03*
X77700Y502500D03*
X88573Y503935D03*
X70910Y502219D03*
X67700Y499120D03*
X77700Y522500D03*
X88204Y543283D03*
X89200Y518700D03*
Y528500D03*
X65600Y543200D03*
X75600Y518600D03*
X67700Y518500D03*
X67162Y515142D03*
X77300Y531238D03*
X77700Y538500D03*
X74301Y538390D03*
X65800Y538900D03*
X74300Y533600D03*
X73900Y527050D03*
X77372Y526885D03*
X73700Y542600D03*
X70000Y542500D03*
X74000Y557000D03*
X77500Y554500D03*
X87337Y569268D03*
X84226Y577924D03*
X87200Y565785D03*
X77400Y550400D03*
X65381Y548719D03*
X87608Y557685D03*
X69100Y549200D03*
X73700Y549300D03*
X92000Y591200D03*
X69500Y586000D03*
X66000Y604800D03*
X88000Y613600D03*
X81000Y589000D03*
X78300Y637750D03*
X94950Y677850D03*
X74500Y713400D03*
X91450Y707650D03*
X65350Y690356D03*
X89400Y749200D03*
X89300Y736300D03*
X95400Y731600D03*
Y728200D03*
X68900Y730000D03*
X68465Y736229D03*
X85800Y727500D03*
Y731000D03*
X74300Y769950D03*
X89800Y753400D03*
X69800Y772700D03*
X86900Y757900D03*
X89400Y762400D03*
X93100Y813200D03*
X93300Y818900D03*
X108631Y168836D03*
X111967Y199632D03*
X119800Y234531D03*
X103100Y211600D03*
X109600Y276850D03*
X112732Y272786D03*
X107340Y266140D03*
X101463Y268811D03*
X102499Y281183D03*
X108500Y284000D03*
X107213Y301192D03*
X120700Y282400D03*
X100500Y285300D03*
X113915Y307600D03*
X117484D03*
X101630Y312236D03*
X106717Y335600D03*
X117700Y323400D03*
X111900Y344200D03*
X113000Y336000D03*
X107558Y321012D03*
X122000Y343300D03*
X100277Y336077D03*
X102000Y364700D03*
X122645Y367966D03*
X117300Y361700D03*
X115951Y384138D03*
X111950Y392050D03*
X104204Y383661D03*
X129500Y412400D03*
X124290Y401910D03*
X125718Y383302D03*
X125600Y386700D03*
X107358Y409942D03*
X126122Y432323D03*
X116235Y444665D03*
X103179Y423267D03*
X103176Y434180D03*
X110406Y417067D03*
X113518Y420179D03*
X131304Y418855D03*
X131004Y422710D03*
X130633Y444763D03*
X120200Y436400D03*
X120000Y451285D03*
X107900Y448900D03*
X101200Y470400D03*
X129520Y448660D03*
X127820Y452280D03*
X123696Y454452D03*
X114400Y550000D03*
X102870Y565740D03*
Y561340D03*
X105851Y611436D03*
X102000Y602500D03*
X101750Y595600D03*
X128220Y620392D03*
X125581Y641436D03*
X109051Y645936D03*
X124150Y707050D03*
X106900Y738600D03*
Y721300D03*
X115000Y717600D03*
X107000Y717800D03*
X111300Y756000D03*
X109900Y828800D03*
X105400Y828700D03*
X103200Y825400D03*
X115500Y825500D03*
X107600D03*
X120000Y843500D03*
X126500Y878200D03*
Y871000D03*
X129000Y875000D03*
X117500Y878200D03*
X122000D03*
X124500Y875000D03*
X120000Y865000D03*
Y875000D03*
Y853500D03*
X162500Y173500D03*
X155026Y212580D03*
X155662Y266438D03*
X159662Y266600D03*
X162910Y244290D03*
X166087Y304350D03*
X134800Y329600D03*
X144595Y312861D03*
X137862Y361723D03*
X161311Y371428D03*
X141216Y361163D03*
X145027D03*
X156573Y371799D03*
X146105Y403610D03*
X155657Y384291D03*
X137000Y436700D03*
X145901Y441262D03*
X153100Y439000D03*
X136500Y417400D03*
X152978Y435602D03*
X137344Y446737D03*
X137000Y451300D03*
X163440Y453020D03*
X143547Y477976D03*
X137000Y454700D03*
X159239Y449079D03*
X159082Y452509D03*
X153019Y622720D03*
X159716Y620392D03*
X166015D03*
X136651Y653036D03*
X162100Y677800D03*
X164400Y668300D03*
X160500Y689500D03*
X150000Y701500D03*
X142500Y709000D03*
X137000Y715500D03*
X164500Y693500D03*
X144400Y731600D03*
Y728200D03*
X150450Y744150D03*
X146450Y736150D03*
X135700Y745200D03*
X163800Y771000D03*
X160400D03*
X160700Y753400D03*
X139250Y791250D03*
X143250Y799250D03*
X153500Y808500D03*
X163800Y820000D03*
X160400D03*
X191800Y189600D03*
X196018Y204200D03*
X183400Y221600D03*
X171100Y247500D03*
X167600Y247600D03*
X193303Y264310D03*
X167700Y296882D03*
Y292517D03*
X170062Y304556D03*
X174943Y321015D03*
X167687Y329434D03*
X192407Y320262D03*
X180571Y327023D03*
X176674Y344934D03*
X189365Y329905D03*
X179381Y369903D03*
X196529Y352284D03*
X185970Y358962D03*
X195940Y348814D03*
X182969Y352641D03*
X192150Y406429D03*
X197000Y404000D03*
X171434Y398093D03*
X177550Y407850D03*
X166321Y388316D03*
X197850Y437450D03*
X185000Y419900D03*
X197531Y451187D03*
X189381Y451394D03*
X193718D03*
X196239Y462262D03*
X175912Y450747D03*
X166534Y450821D03*
X186675Y453505D03*
X177500Y454300D03*
X199900Y544500D03*
X196782Y563564D03*
X197334Y567232D03*
X189500Y567700D03*
X185500Y577300D03*
X184189Y564504D03*
X185500Y567700D03*
X193001Y574708D03*
X181000Y585000D03*
Y581500D03*
Y595200D03*
X168769Y622720D03*
X171300Y678300D03*
X175200Y678500D03*
X199900Y692000D03*
X171000Y715900D03*
X167600D03*
X178750Y712250D03*
X189000Y684500D03*
X185000D03*
X167000Y686500D03*
X199900Y747500D03*
Y741000D03*
X184700Y729400D03*
X182750Y720250D03*
X193000Y729500D03*
X171000Y764900D03*
X167600D03*
X182750Y775750D03*
X178000Y753400D03*
X178750Y767750D03*
X199900Y796500D03*
X177500Y784500D03*
X170800Y808500D03*
X193000Y785000D03*
X197420Y821701D03*
X194120Y830301D03*
X190920D03*
X176900Y867600D03*
X173500D03*
X197218Y871676D03*
X228163Y68589D03*
X222354Y103006D03*
X228163Y78589D03*
X227606Y98642D03*
X223641Y99302D03*
X228163Y93589D03*
Y88589D03*
X228007Y123787D03*
X233500Y137000D03*
X220300Y129300D03*
X222356Y133438D03*
X228708Y127115D03*
X215136Y142786D03*
X218299Y123319D03*
X224576Y116678D03*
X221418Y109634D03*
X210478Y151203D03*
X233537Y160630D03*
X210484Y179525D03*
X206297Y188492D03*
X209866D03*
X214794Y212100D03*
X206200Y247500D03*
X209200Y252800D03*
X230400Y283400D03*
X222200Y300500D03*
X205840Y325381D03*
X210177D03*
X221460Y335475D03*
Y339875D03*
X228100Y364600D03*
X219018Y378000D03*
X223383D03*
X217000Y360000D03*
X219580Y356970D03*
X214776Y352807D03*
X212536Y349805D03*
X205750Y408250D03*
X205915Y422424D03*
X217190Y428485D03*
X212200Y428800D03*
X212000Y438713D03*
X217500Y441992D03*
X205200Y442900D03*
X220897Y441833D03*
X220800Y446000D03*
X200100Y415100D03*
X201868Y451187D03*
X227700Y476537D03*
Y472200D03*
X216404Y469751D03*
X216282Y463288D03*
X230572Y455128D03*
X228900Y446800D03*
X219300Y508700D03*
X228298Y488100D03*
X228347Y484700D03*
X219700Y489800D03*
X202700Y495400D03*
X206700Y498000D03*
X200917Y490578D03*
X203550Y484522D03*
X233290Y493277D03*
X206700Y494000D03*
X203500Y499200D03*
X207026Y483956D03*
X219800Y493700D03*
X218906Y483186D03*
X226300Y505700D03*
X226530Y502307D03*
X216873Y516458D03*
X203300Y538500D03*
X206700Y544500D03*
Y538500D03*
X225000Y541300D03*
X229200Y514800D03*
X216300Y546350D03*
X203300Y544500D03*
Y548500D03*
X219700Y550500D03*
X218780Y560082D03*
X206700Y548500D03*
X202300Y559763D03*
X222300Y577300D03*
X216563Y555908D03*
X229800Y558500D03*
X206700Y554500D03*
X203304Y554684D03*
X205700Y559763D03*
X222500Y573220D03*
X216241Y563095D03*
X227500Y603500D03*
X201000Y674000D03*
X206952Y655370D03*
X203300Y692000D03*
X219000Y694000D03*
X231500Y699000D03*
X217000Y705500D03*
X203300Y747500D03*
Y741000D03*
X210300Y729500D03*
X217000Y761000D03*
X228550Y772700D03*
X231750D03*
X203300Y796500D03*
X210300Y785000D03*
X200620Y821701D03*
X231915Y830301D03*
X219317D03*
X206718D03*
X228715D03*
X216117D03*
X203518D03*
X225615Y875176D03*
X213017D03*
X200418Y871676D03*
X222415Y875176D03*
X209817D03*
X257759Y68589D03*
X264817Y105350D03*
X257731Y78589D03*
X258100Y93589D03*
X257912Y101408D03*
X258029Y97353D03*
X260562Y85988D03*
X254000Y131500D03*
X246500Y139000D03*
X243000D03*
X258068Y110180D03*
X259331Y118580D03*
X264443Y109587D03*
X257422Y121792D03*
X243618Y143381D03*
X243500Y147500D03*
X244300Y226700D03*
X266500Y239400D03*
X245400Y296500D03*
X248160Y343140D03*
X267300Y362200D03*
X244000Y377617D03*
Y381982D03*
X258500Y391200D03*
X239100Y399200D03*
X251700Y421600D03*
Y425200D03*
X238400Y416200D03*
X235750Y419500D03*
X262900Y438700D03*
X246375Y440725D03*
X265100Y443300D03*
X264100Y425400D03*
X249342Y439064D03*
X251800Y470100D03*
X248500Y465000D03*
X263700Y474600D03*
X257493Y456679D03*
X253302D03*
X257400Y477300D03*
X235850Y455050D03*
X246300Y478600D03*
Y485400D03*
X246407Y488799D03*
X256300Y494500D03*
X244100Y499900D03*
X246800Y496800D03*
X257400Y481637D03*
X256300Y486000D03*
Y490000D03*
X242800Y495486D03*
X246500Y493400D03*
X240450Y499400D03*
X236737Y493170D03*
X243200Y508000D03*
X250200Y506600D03*
X264522Y511690D03*
X260407Y502674D03*
X257207D03*
X246300Y482000D03*
X239139Y525077D03*
X239321Y521081D03*
X264500Y521309D03*
X261100Y521250D03*
X250100Y537100D03*
X236100Y517100D03*
X263300Y526300D03*
X234777Y550569D03*
X255738Y574238D03*
X253500Y590500D03*
X257413D03*
X236000Y656000D03*
X256600Y652200D03*
X241000Y712500D03*
X262628Y744470D03*
X266980Y723854D03*
X241000Y721500D03*
X258100Y726100D03*
X241000Y725500D03*
Y718000D03*
X263181Y772181D03*
X266561Y830301D03*
X253962D03*
X263361D03*
X250762D03*
X260261Y875176D03*
X238213D03*
X257061D03*
X235013D03*
X290000Y141100D03*
X274250Y133750D03*
X292000Y130000D03*
X285500D03*
X284440Y139580D03*
X285250Y133750D03*
X294500Y152500D03*
X286000Y143800D03*
X286100Y153900D03*
X280000D03*
X290500Y152500D03*
X275000Y147500D03*
X277800Y208500D03*
X271231Y237031D03*
X283622Y226340D03*
X279257D03*
X277300Y304800D03*
X297090Y311350D03*
X282700Y300100D03*
X299600Y297662D03*
X287200Y326802D03*
X287800Y311600D03*
X267979Y342500D03*
X295400Y325390D03*
X283700Y322100D03*
X288270Y365240D03*
X297729Y351029D03*
X294009Y363063D03*
X293800Y436100D03*
X301170Y462780D03*
X301162Y459290D03*
X273783Y476100D03*
X283400Y477900D03*
X275900Y467300D03*
X285800Y460810D03*
X290838Y501600D03*
X286169Y502000D03*
X285776Y489300D03*
X272860Y489147D03*
X282400Y487300D03*
X295876Y520800D03*
X296200Y566900D03*
X290000Y578165D03*
X279994Y554794D03*
X283600Y551400D03*
X291000Y561450D03*
X280200Y551400D03*
X289835Y583165D03*
Y588165D03*
X269000Y589000D03*
X269335Y593165D03*
X297750Y592750D03*
X281800Y638900D03*
X288400Y626100D03*
Y634200D03*
X292500Y630200D03*
X271500Y639500D03*
X298406Y706000D03*
X290338Y715800D03*
X275609Y726886D03*
X270556Y716702D03*
X269500Y736150D03*
X286500Y740500D03*
X287278Y729031D03*
X286406Y716531D03*
X296132Y726171D03*
X290720Y726333D03*
X285333Y726241D03*
X282406Y716598D03*
X298620Y728596D03*
X283500Y765631D03*
X268193Y755633D03*
X293692Y765571D03*
X287115Y765584D03*
X281500Y752000D03*
X299184Y765691D03*
X279159Y830301D03*
X275959D03*
X285500Y866200D03*
X272859Y875176D03*
X282300Y866200D03*
X269659Y875176D03*
X306900Y251000D03*
X302500Y251600D03*
X311882Y310550D03*
X306800Y290500D03*
X307425Y309838D03*
X303517Y309777D03*
X312900Y290450D03*
X321300Y301500D03*
X334200Y299600D03*
X313200Y299900D03*
X331800Y309100D03*
X310485Y314670D03*
X328800Y315900D03*
X326041Y325000D03*
X310839Y344339D03*
X315300Y344500D03*
X315900Y320900D03*
X313100Y371038D03*
Y374438D03*
X301320Y362500D03*
X301929Y351100D03*
X313500Y437400D03*
Y441000D03*
X313300Y429603D03*
X313294Y434006D03*
X302140Y444160D03*
X306521Y463576D03*
X304293Y466146D03*
X329014Y472022D03*
X322268Y466591D03*
X322305Y469991D03*
X321900Y459800D03*
X322036Y463198D03*
X327512Y509612D03*
X303800Y505100D03*
X304400Y511400D03*
X327589Y504300D03*
X333102Y485902D03*
X330000Y501900D03*
X305500Y483550D03*
X320500Y531000D03*
X321000Y527000D03*
X306900Y529100D03*
X311500Y548000D03*
X314900D03*
X309000Y679000D03*
X305500Y676400D03*
X334800Y712000D03*
X302406Y706031D03*
X306406D03*
X317300Y739300D03*
X302000Y740800D03*
X320000Y718200D03*
X323600Y717800D03*
X301310Y726403D03*
X326000Y729000D03*
X315132Y727197D03*
X307278Y726198D03*
X311200Y765500D03*
X311406Y775198D03*
X302700Y765400D03*
X315406Y765598D03*
Y775200D03*
X307406Y775198D03*
X329553Y830301D03*
X316954D03*
X326353D03*
X313754D03*
X323253Y875176D03*
X310955Y865676D03*
X332651Y875176D03*
X320053D03*
X307755Y865676D03*
X362528Y123931D03*
X358917Y124122D03*
X355069D03*
X352600Y128200D03*
Y132537D03*
X337000Y162000D03*
X354800Y171400D03*
X358300D03*
X354800Y166900D03*
X358300D03*
X354800Y162400D03*
X358300D03*
X362300D03*
Y166900D03*
Y171400D03*
X354800Y181900D03*
X358300D03*
X354800Y176900D03*
X358300D03*
X362300D03*
Y181900D03*
X345820Y256570D03*
X349970Y256720D03*
X341652Y305034D03*
Y301534D03*
X362500Y341700D03*
X362825Y336000D03*
X359132Y326647D03*
X351515Y327915D03*
X356953Y353653D03*
X359403Y351203D03*
X352003Y358603D03*
X354505Y356102D03*
X360820Y359299D03*
X363270Y356940D03*
X355872Y363965D03*
X358362Y361649D03*
X335570Y491460D03*
X367000Y704000D03*
X360000D03*
X344200Y696300D03*
X354300Y696000D03*
Y704500D03*
X363500Y704000D03*
X364354Y731801D03*
X362091Y729538D03*
X367675Y723000D03*
X367348Y830301D03*
X354750D03*
X342151D03*
X364148D03*
X351550D03*
X338951D03*
X361048Y875176D03*
X348450D03*
X335851D03*
X357848D03*
X345250D03*
X401300Y156715D03*
Y153215D03*
X400400Y189100D03*
X383600Y203200D03*
X376600Y261350D03*
X381700Y265800D03*
X368900Y315700D03*
X370700Y353900D03*
X370500Y705500D03*
X370875Y723000D03*
X401994Y830301D03*
X389396D03*
X398794D03*
X386196D03*
X395694Y875176D03*
X383096D03*
X392494D03*
X379896D03*
X403600Y142542D03*
X433000Y169700D03*
X435161Y166892D03*
X403600Y146042D03*
X422876Y199830D03*
Y204195D03*
X421757Y177999D03*
X411400Y183900D03*
X433400Y176800D03*
X410900Y217100D03*
X404040Y318900D03*
Y323300D03*
X427191Y830301D03*
X414593D03*
X423991D03*
X411393D03*
X420891Y875176D03*
X408292D03*
X417691D03*
X405092D03*
X466000Y62300D03*
X457700D03*
X465127Y57727D03*
X454926Y118791D03*
X455800Y110200D03*
X438561Y166892D03*
X456500Y169783D03*
Y165418D03*
X464086Y287614D03*
Y340500D03*
X455450Y376050D03*
X469700Y393300D03*
X459450Y384050D03*
X469000Y784000D03*
X461300Y813100D03*
X457900D03*
X474400Y62300D03*
X483250Y59480D03*
X496782Y134315D03*
X474990Y122660D03*
X480910Y164099D03*
X480800Y160700D03*
X498900Y171800D03*
X498000Y194200D03*
X477037Y333841D03*
X473637Y333876D03*
X500198Y324041D03*
X480532Y321332D03*
X480000Y355800D03*
X476600D03*
X493700Y369300D03*
X487000Y393300D03*
X480368Y405606D03*
X476531D03*
X482925Y777422D03*
X489522Y780127D03*
X478000Y777500D03*
X483850Y773800D03*
X500778Y781031D03*
X499906Y768531D03*
X497910Y778824D03*
X495906Y768598D03*
X480100Y784575D03*
X497000Y817500D03*
X483000Y788150D03*
X499000Y793000D03*
X485300Y811750D03*
X500415Y817532D03*
X494582Y804000D03*
X477206Y820648D03*
X500700Y828100D03*
X500807Y831499D03*
X491906Y827403D03*
X487906D03*
X509369Y141559D03*
X530800Y123900D03*
X507861Y134154D03*
X519300Y138871D03*
X530177Y140708D03*
X516100Y138871D03*
X526977Y140708D03*
X529176Y151713D03*
X532560Y152046D03*
X534000Y167400D03*
X535960Y151999D03*
X507300Y175500D03*
X503975Y172372D03*
X518686Y163800D03*
Y168200D03*
X517599Y229658D03*
X531232Y229927D03*
X510462Y261315D03*
X525881Y287776D03*
X509143Y284391D03*
X529881Y287376D03*
X529126Y342336D03*
X532978Y371023D03*
X534500Y395100D03*
X528850Y394750D03*
X515900Y768300D03*
X531500Y774500D03*
X531600Y770200D03*
X515278Y779198D03*
X519748Y768297D03*
X507729Y778198D03*
X504278Y779198D03*
X507906Y768531D03*
X528179Y782555D03*
X524795Y778529D03*
X511484Y778515D03*
X515650Y764500D03*
X503906Y768598D03*
X519906Y764900D03*
X532000Y792500D03*
X515000D03*
X524700Y817500D03*
X507044Y817569D03*
X516943Y817401D03*
X528906Y817598D03*
X512716Y817550D03*
X508579Y827421D03*
X527500Y836200D03*
X512679Y827500D03*
X562603Y140881D03*
X544800Y137769D03*
X541600D03*
X549100Y126900D03*
X566531Y143123D03*
X570754Y147365D03*
X546800Y163450D03*
X564483Y167935D03*
X558121Y167249D03*
X548700Y152200D03*
X545500D03*
X547173Y167987D03*
X561567Y205767D03*
X569500Y240225D03*
X546494Y216010D03*
X539798Y228856D03*
X539934Y232660D03*
X540035Y236294D03*
X541637Y263240D03*
X545974D03*
X541681Y297976D03*
X539481Y286676D03*
X544993Y281352D03*
X539400Y376444D03*
X561300Y369500D03*
X552720Y364180D03*
X539400Y380781D03*
X559973Y387638D03*
X561912Y390762D03*
X567150Y415750D03*
X560900Y413700D03*
X544000Y761000D03*
X540500Y781000D03*
X547395Y761198D03*
X540500Y761000D03*
X561050Y830301D03*
X548451D03*
X570448D03*
X557850D03*
X545251D03*
X567348Y875176D03*
X554750D03*
X542151D03*
X564148D03*
X551550D03*
X538951D03*
X577650Y137780D03*
X587850Y137800D03*
X604450Y137780D03*
X574450D03*
X584650Y137800D03*
X601250Y137780D03*
X597350Y149950D03*
X594150D03*
X596253Y210000D03*
X603000Y190710D03*
X579811Y179500D03*
X582400Y209500D03*
X597813Y220858D03*
X587438Y230850D03*
X576100Y234500D03*
X592563Y228308D03*
X588963Y227408D03*
X587400Y238200D03*
X600800Y337400D03*
X597600Y339100D03*
X604400Y421200D03*
X579900Y427400D03*
X598845Y830301D03*
X586246D03*
X573648D03*
X595645D03*
X583046D03*
X592545Y875176D03*
X579947D03*
X601944D03*
X589345D03*
X576747D03*
X614721Y138287D03*
X608089Y131519D03*
X627826Y137880D03*
X638150D03*
X624626D03*
X634950D03*
X617000Y144500D03*
X636950Y149650D03*
X635482Y207733D03*
X607700Y211800D03*
X608800Y221400D03*
X635863Y216308D03*
X635190Y219641D03*
X631063Y242108D03*
X616970Y235017D03*
X629663Y221708D03*
X616718Y238408D03*
X627363Y224358D03*
X637300Y234500D03*
X628563Y249108D03*
X624101Y330010D03*
X627500Y329900D03*
X622629Y344635D03*
X616640Y342230D03*
X620000Y341500D03*
X618600Y357100D03*
X609000Y390350D03*
X615500Y420100D03*
X619100Y418000D03*
X636640Y830301D03*
X624042D03*
X611443D03*
X633440D03*
X620842D03*
X608243D03*
X630340Y875176D03*
X617742D03*
X605144D03*
X627140D03*
X614542D03*
X654500Y143000D03*
X647000D03*
X640150Y149650D03*
X640400Y218200D03*
X649400Y234500D03*
X642463Y241608D03*
X638963D03*
X660700Y212000D03*
X643000Y343000D03*
X643750Y321500D03*
X640550D03*
X643000Y369500D03*
X648792Y358431D03*
X660244Y352200D03*
Y349000D03*
X645800Y780500D03*
Y776900D03*
Y783900D03*
X671285Y830301D03*
X658687D03*
X668085D03*
X655487D03*
X664986Y875176D03*
X652388D03*
X661786D03*
X649188D03*
X687900Y208100D03*
X697494Y186256D03*
Y181919D03*
X693300Y181200D03*
X674500Y212000D03*
X680100Y378718D03*
X683600D03*
X696482Y830301D03*
X683884D03*
X693282D03*
X680684D03*
X702400Y868800D03*
X690183Y875176D03*
X677585D03*
X699200Y868800D03*
X686983Y875176D03*
X674385D03*
X728395Y-7315D03*
X713461Y-3006D03*
X729132Y3575D03*
X724018Y5719D03*
X729000Y24800D03*
X725314Y24751D03*
X721890Y24887D03*
X719008Y21999D03*
X707051Y12174D03*
X738384Y8232D03*
X722955Y33095D03*
X726155D03*
X723200Y42300D03*
X726609Y49251D03*
Y46051D03*
X732900Y44900D03*
X730021Y42235D03*
X732500Y98421D03*
X720800Y102150D03*
Y93150D03*
Y78150D03*
X732500Y101621D03*
X720800Y105350D03*
Y96350D03*
Y81350D03*
Y114150D03*
Y117350D03*
X713000Y310000D03*
X712495Y816195D03*
X727978Y830301D03*
X737377D03*
X724778D03*
X714900Y818600D03*
X734277Y875176D03*
X731077D03*
X746329Y-7789D03*
X771715Y6840D03*
X741600Y41000D03*
X742290Y68550D03*
X750130Y63340D03*
X748300Y53800D03*
X772000Y64200D03*
X755700Y79100D03*
X749800Y91400D03*
X753700Y102900D03*
X759600Y79200D03*
X743490Y111940D03*
X765000Y112800D03*
X768777Y171450D03*
X761242Y169242D03*
X765579D03*
X766950Y189252D03*
X763562Y189539D03*
X770385Y189165D03*
X749337Y212192D03*
X746037Y213992D03*
X746237Y210392D03*
X765774Y830301D03*
X753175D03*
X740577D03*
X762574D03*
X749975D03*
X772073Y875176D03*
X759474D03*
X746876D03*
X768873D03*
X756274D03*
X743676D03*
X790150Y-1400D03*
X788408Y-4321D03*
X798061Y-6439D03*
X806152Y51692D03*
X791300Y74200D03*
X775381Y66115D03*
X778800Y66388D03*
X782551Y67144D03*
X786333Y66963D03*
X791200Y125300D03*
X806665Y174050D03*
X803265D03*
X792760Y176043D03*
X799000Y196000D03*
X802200D03*
X792000Y195778D03*
X787600Y195804D03*
X773984Y189118D03*
X792760Y180443D03*
X778807Y183890D03*
Y179490D03*
X803569Y830301D03*
X790970D03*
X778372D03*
X800369D03*
X787770D03*
X775172D03*
X797270Y875176D03*
X784671D03*
X806668D03*
X794070D03*
X781471D03*
X807514Y2199D03*
X813900Y12900D03*
X838252Y20800D03*
X834500D03*
X830500D03*
X828283Y24734D03*
X824462Y25770D03*
X821877Y21090D03*
X823996Y44276D03*
X820004Y44234D03*
X828700Y48800D03*
X808114Y67634D03*
X816043Y94981D03*
Y99318D03*
X823551Y80551D03*
X819000Y97100D03*
X809000Y76000D03*
X810000Y109400D03*
X840500Y735500D03*
X837000D03*
X839990Y789230D03*
X816167Y830301D03*
X838164D03*
X812967D03*
X835065Y875176D03*
X809868D03*
X831865D03*
X861000Y350D03*
X857453Y303D03*
X863300Y23575D03*
X851100Y9100D03*
X849051Y20908D03*
X845052Y20800D03*
X841652D03*
X858500Y28000D03*
X858100Y21400D03*
X858500Y36000D03*
X847000Y9100D03*
X870600Y18915D03*
X854252Y20800D03*
X851870Y52160D03*
X848623Y70757D03*
X852019Y70589D03*
X855421Y70551D03*
X858821Y70614D03*
X859000Y43500D03*
X871550Y56450D03*
X858800Y52200D03*
X868800Y49200D03*
Y85300D03*
X871696Y87082D03*
X868200Y116000D03*
X846702Y117371D03*
X854400Y117500D03*
X861300Y117800D03*
X864800Y707700D03*
X868200D03*
X852895Y748648D03*
X869406Y745531D03*
X848000Y735500D03*
X865406Y745598D03*
X873367Y745335D03*
X844000Y735500D03*
X854049Y757573D03*
X857406Y755198D03*
X861406D03*
X858126Y763600D03*
X841500Y771000D03*
X874000Y772000D03*
X869562Y758457D03*
X844500Y758000D03*
X867410Y755824D03*
X866878Y794531D03*
X853500Y798000D03*
X846706Y797648D03*
X870278Y794531D03*
X874570Y811820D03*
X861406Y804403D03*
X857406D03*
X853962Y830301D03*
X841364D03*
X850762D03*
X847663Y875176D03*
X844463D03*
X883800Y-500D03*
X881700Y2300D03*
X899769Y4355D03*
X896500Y9500D03*
X877500Y23600D03*
X900250Y38150D03*
X888474Y9173D03*
X900200Y9600D03*
X883800Y41400D03*
X900501Y48705D03*
X883700Y50700D03*
X905488Y54479D03*
X878394Y85780D03*
X875001Y86003D03*
X901899Y85942D03*
X892900Y85300D03*
X885042Y85292D03*
X888600Y85700D03*
X897600Y85500D03*
X895800Y738400D03*
X893400Y745100D03*
X884700Y721100D03*
X896500Y734000D03*
X877000Y745000D03*
X892100Y721100D03*
X881200Y721300D03*
X888400Y721400D03*
X889900Y769600D03*
X884778Y756198D03*
X876036Y755481D03*
X894465Y755501D03*
X891056Y755641D03*
X882227Y758835D03*
X894200Y794500D03*
X877930Y796880D03*
X876470Y808710D03*
X906396Y810300D03*
X886288Y794372D03*
X898700Y794200D03*
Y816000D03*
X882290Y796770D03*
X881720Y807390D03*
X906450Y806900D03*
X906092Y813687D03*
X894406Y818000D03*
X888100Y823338D03*
X890200Y819200D03*
X911800Y37000D03*
X938000Y30300D03*
X919400Y33300D03*
X915486Y41030D03*
X918952Y40680D03*
X939064Y58104D03*
X934881Y57322D03*
X909797Y55037D03*
X910000Y85300D03*
X937642Y85562D03*
X926093Y85239D03*
X929213Y86593D03*
X934438Y86700D03*
X919050Y85500D03*
X913979Y86580D03*
X929800Y105900D03*
X974100Y19600D03*
X970064Y18764D03*
X963700Y21700D03*
X959877Y26978D03*
X967180Y66705D03*
X949102Y74964D03*
X947900Y67900D03*
X959300Y68600D03*
Y72000D03*
X964105Y62308D03*
X959855Y61107D03*
X956687Y85482D03*
X942800Y85700D03*
X948200Y85900D03*
X953301Y85793D03*
X949893Y106378D03*
X949828Y109778D03*
X960500Y607000D03*
X953500D03*
X956900D03*
X1008353Y-1940D03*
X985579Y26494D03*
X985403Y22993D03*
X994650Y39880D03*
X990628Y49698D03*
X997007Y49560D03*
X1008508Y47704D03*
X1022711Y-4975D03*
X1012177Y-2940D03*
X1019859Y-7642D03*
X1033017Y14743D03*
X1033554Y30216D03*
X1040121Y26870D03*
X1039822Y35743D03*
X1017908Y41556D03*
X1018900Y14198D03*
X1010975Y29017D03*
X1029553Y13981D03*
X1030139Y30209D03*
X1024432Y43718D03*
X1011300Y53000D03*
X1024318Y51554D03*
X1014700Y53700D03*
X1040241Y61043D03*
X1033517Y48934D03*
X1036854Y47110D03*
X1019900Y108500D03*
X1015948D03*
X1034500D03*
X1027483Y108431D03*
X1024000Y108500D03*
X1037900D03*
X1041300D03*
X1030883Y108438D03*
X1028500Y257500D03*
X1041314Y830301D03*
X1038214Y875176D03*
X1035014D03*
X1062044Y-4173D03*
X1065620Y-4335D03*
X1072800Y-800D03*
X1045850Y6228D03*
X1069200Y-4200D03*
X1060800Y10100D03*
X1044050Y28815D03*
X1062088Y40597D03*
X1072804Y19894D03*
X1064900Y10400D03*
X1065700Y32888D03*
Y36088D03*
X1061200Y20888D03*
Y24088D03*
X1056200Y10100D03*
X1065657Y28946D03*
X1047500Y41500D03*
X1051000D03*
X1076970Y30411D03*
X1052600Y14400D03*
X1049772Y57259D03*
X1049470Y53749D03*
X1050875Y61090D03*
X1057000Y54500D03*
X1071135Y60375D03*
X1057000Y57700D03*
X1071135Y57175D03*
X1057000Y107700D03*
X1057259Y77276D03*
X1048100Y108500D03*
X1044700D03*
X1061000Y111000D03*
X1053000Y109500D03*
X1069711Y830301D03*
X1057112D03*
X1044514D03*
X1066511D03*
X1053912D03*
X1076010Y875176D03*
X1050813D03*
X1072810D03*
X1047613D03*
X1084000Y500D03*
X1083315Y36654D03*
X1082808Y30601D03*
X1092094Y30362D03*
X1080672Y9500D03*
X1084800Y9400D03*
X1083379Y40889D03*
X1083500Y25500D03*
X1082974Y14467D03*
X1105441Y54768D03*
X1100992Y52374D03*
X1078694Y43478D03*
X1077432Y64225D03*
X1103300Y73900D03*
X1103349Y70700D03*
X1088005Y46541D03*
X1088287Y55917D03*
X1096496Y51226D03*
X1107506Y830301D03*
X1094907D03*
X1082309D03*
X1104306D03*
X1091707D03*
X1079109D03*
X1101207Y875176D03*
X1088608D03*
X1110605D03*
X1098007D03*
X1085408D03*
X1112700Y80700D03*
X1114842Y83078D03*
X1122001Y133324D03*
X1141900Y137851D03*
X1122001Y130124D03*
X1138700Y137851D03*
X1143000Y242000D03*
X1132703Y830301D03*
X1120104D03*
X1142101D03*
X1129503D03*
X1116904D03*
X1139002Y875176D03*
X1126403D03*
X1113805D03*
X1135802D03*
X1123203D03*
X1161307Y138505D03*
X1158107D03*
X1170400Y144100D03*
X1147000Y242000D03*
X1151000D03*
X1157899Y830301D03*
X1145301D03*
X1176747D03*
X1154699D03*
X1164199Y875176D03*
X1151600D03*
X1160999D03*
X1148400D03*
X1182061Y142478D03*
X1190835Y137899D03*
X1199400Y142851D03*
X1178861Y142478D03*
X1187635Y137899D03*
X1196200Y142851D03*
X1206991Y156730D03*
X1203791D03*
X1201000Y417900D03*
X1196600Y416200D03*
X1192545Y830301D03*
X1179947D03*
X1189345D03*
X1199000Y867200D03*
X1186246Y875176D03*
X1195800Y867300D03*
X1183046Y875176D03*
X1214795Y142443D03*
X1234209Y142463D03*
X1242900Y137851D03*
X1225348Y137960D03*
X1231009Y142463D03*
X1239700Y137851D03*
X1222148Y137960D03*
X1242621Y153690D03*
X1226000Y261300D03*
X1236640Y830301D03*
X1224042D03*
X1233440D03*
X1220842D03*
X1242939Y875176D03*
X1230340D03*
X1239739D03*
X1227140D03*
X1277265Y137673D03*
X1274065D03*
X1273499Y151498D03*
X1273520Y148070D03*
X1261944Y145770D03*
X1258744D03*
X1251801Y144871D03*
X1275500Y264500D03*
X1255000Y317300D03*
X1270500Y335500D03*
X1272500Y350000D03*
X1275060Y345690D03*
X1277620Y349500D03*
X1264820Y349320D03*
X1249250Y390250D03*
X1269500Y397000D03*
X1273500Y400500D03*
X1258000Y421500D03*
X1274435Y830301D03*
X1261837D03*
X1249239D03*
X1271235D03*
X1258637D03*
X1246039D03*
X1268136Y875176D03*
X1255537D03*
X1277534D03*
X1264936D03*
X1252337D03*
X1303983Y22083D03*
X1304000Y44000D03*
Y67500D03*
Y90500D03*
X1286543Y141581D03*
X1296017Y137478D03*
X1283343Y141581D03*
X1292817Y137478D03*
X1290000Y271000D03*
X1308500Y262500D03*
X1311200Y256500D03*
X1293500Y271000D03*
X1312200Y275200D03*
X1303700Y289500D03*
X1288900Y304000D03*
X1283300Y302900D03*
X1309900Y292400D03*
X1310500Y285500D03*
X1281900Y346580D03*
X1282740Y350010D03*
X1293280Y345770D03*
X1289960Y349900D03*
X1299000Y347500D03*
X1311500Y391000D03*
X1310068Y394084D03*
X1297625Y382375D03*
X1296500Y386500D03*
X1290125Y382875D03*
X1289500Y386500D03*
X1282740Y383000D03*
X1282000Y386500D03*
X1301000Y618500D03*
X1300000Y637000D03*
X1297617Y677117D03*
X1286800Y671100D03*
X1297500Y664000D03*
X1310207D03*
X1297400Y651300D03*
X1290550D03*
X1302000Y695500D03*
X1302128Y685500D03*
X1307000Y686500D03*
X1304500Y698000D03*
X1301728Y714600D03*
X1312132Y684293D03*
X1310500Y723000D03*
X1291428Y726117D03*
X1306128Y732872D03*
X1302128D03*
X1312231Y830301D03*
X1287033D03*
X1309031D03*
X1283833D03*
X1305931Y875176D03*
X1293333D03*
X1280734D03*
X1302731D03*
X1290133D03*
X1339471Y139268D03*
X1316590Y147210D03*
X1317400Y143620D03*
X1340130Y145980D03*
X1331243Y182198D03*
X1322000Y276500D03*
X1322500Y266800D03*
X1333500Y290500D03*
X1317026Y304858D03*
X1314000Y286500D03*
X1313607Y664000D03*
X1327200Y661800D03*
X1331000Y662000D03*
X1326128Y674000D03*
X1340000D03*
X1317007Y664000D03*
X1334128Y674000D03*
X1337500Y698000D03*
X1322439Y697767D03*
X1315000Y686500D03*
X1329500Y684667D03*
X1321928Y683798D03*
X1318500Y684667D03*
X1339934Y683832D03*
X1336795Y685141D03*
X1326758Y686678D03*
X1314628Y733000D03*
X1315000Y723000D03*
X1333500D03*
X1334128Y732667D03*
X1325600Y722987D03*
X1342000Y732500D03*
X1337500Y723000D03*
X1340500Y742500D03*
X1338128Y732872D03*
X1330128Y732667D03*
X1337427Y830301D03*
X1324829D03*
X1346825D03*
X1334227D03*
X1321629D03*
X1343726Y875176D03*
X1331128D03*
X1318529D03*
X1340526D03*
X1327928D03*
X1315329D03*
X1359128Y167226D03*
X1355321Y172119D03*
X1354971Y167446D03*
X1365804Y185197D03*
X1355066Y275228D03*
X1348500Y276500D03*
X1361500Y273500D03*
X1352000Y276700D03*
X1352500Y267000D03*
X1369300Y259300D03*
X1355000Y286300D03*
X1364000Y280500D03*
X1351500Y675000D03*
X1350025Y830301D03*
X1381696Y173459D03*
X1387196Y174160D03*
X1382138Y184129D03*
X1385467Y180543D03*
G54D24*
X131700Y275700D03*
X125100Y282500D03*
X131700Y280000D03*
X300500Y715613D03*
G54D21*
X92990Y252362D03*
X116790D03*
X1301120Y173278D03*
Y183908D03*
G54D32*
X473231Y235560D03*
Y274930D03*
G54D36*
X533010Y69803D03*
X535962Y64292D03*
X524151Y69803D03*
X527104Y64292D03*
X535962Y49331D03*
X527104D03*
X533010Y54843D03*
X524151D03*
X533010Y99725D03*
X535962Y94213D03*
X524151Y99725D03*
X527104Y94213D03*
X533010Y84764D03*
X535962Y79252D03*
X524151Y84764D03*
X527104Y79252D03*
X567458Y54843D03*
X570411Y49331D03*
Y64292D03*
X567458Y69803D03*
X541868D03*
X544821Y64292D03*
Y49331D03*
X541868Y54843D03*
X570411Y79252D03*
Y94213D03*
X567458Y84764D03*
Y99725D03*
X541868D03*
X544821Y94213D03*
X541868Y84764D03*
X544821Y79252D03*
X576317Y54843D03*
X585175D03*
X579269Y49331D03*
X588128D03*
X576317Y69803D03*
X585175D03*
X579269Y64292D03*
X588128D03*
X579269Y79252D03*
X588128D03*
X585175Y84764D03*
X576317D03*
Y99725D03*
X585175D03*
X579269Y94213D03*
X588128D03*
X619624Y54843D03*
X628482D03*
X622577Y49331D03*
X631435D03*
X619624Y69803D03*
X628482D03*
X622577Y64292D03*
X631435D03*
X610766Y54843D03*
X613718Y49331D03*
Y64292D03*
X610766Y69803D03*
X622577Y79252D03*
X631435D03*
X628482Y84764D03*
X619624D03*
Y99725D03*
X628482D03*
X622577Y94213D03*
X631435D03*
X613718Y79252D03*
Y94213D03*
X610766Y84764D03*
Y99725D03*
X662931Y54843D03*
X671789D03*
X665884Y49331D03*
X662931Y69803D03*
X671789D03*
X665884Y64292D03*
X654073Y54843D03*
X657025Y49331D03*
Y64292D03*
X654073Y69803D03*
X665884Y79252D03*
X671789Y84764D03*
X662931D03*
Y99725D03*
X671789D03*
X665884Y94213D03*
X657025Y79252D03*
Y94213D03*
X654073Y84764D03*
Y99725D03*
X674742Y49331D03*
Y64292D03*
Y79252D03*
Y94213D03*
X1135372Y69803D03*
X1144230D03*
X1138324Y64292D03*
X1126513Y69803D03*
X1129466Y64292D03*
X1138324Y49331D03*
X1129466D03*
X1144230Y54843D03*
X1135372D03*
X1126513D03*
X1135372Y99725D03*
X1144230D03*
X1138324Y94213D03*
X1126513Y99725D03*
X1129466Y94213D03*
X1135372Y84764D03*
X1144230D03*
X1138324Y79252D03*
X1126513Y84764D03*
X1129466Y79252D03*
X1178679Y54843D03*
Y69803D03*
X1169820Y54843D03*
X1172773Y49331D03*
Y64292D03*
X1169820Y69803D03*
X1147183Y64292D03*
Y49331D03*
X1178679Y84764D03*
Y99725D03*
X1172773Y79252D03*
Y94213D03*
X1169820Y84764D03*
Y99725D03*
X1147183Y94213D03*
Y79252D03*
X1187537Y54843D03*
X1181631Y49331D03*
X1190490D03*
X1187537Y69803D03*
X1181631Y64292D03*
X1190490D03*
X1181631Y79252D03*
X1190490D03*
X1187537Y84764D03*
Y99725D03*
X1181631Y94213D03*
X1190490D03*
X1221986Y54843D03*
X1230844D03*
X1224939Y49331D03*
X1233797D03*
X1221986Y69803D03*
X1230844D03*
X1224939Y64292D03*
X1233797D03*
X1213128Y54843D03*
X1216080Y49331D03*
Y64292D03*
X1213128Y69803D03*
X1224939Y79252D03*
X1233797D03*
X1230844Y84764D03*
X1221986D03*
Y99725D03*
X1230844D03*
X1224939Y94213D03*
X1233797D03*
X1216080Y79252D03*
Y94213D03*
X1213128Y84764D03*
Y99725D03*
X1265293Y54843D03*
X1274151D03*
X1268246Y49331D03*
X1277104D03*
X1265293Y69803D03*
X1274151D03*
X1268246Y64292D03*
X1277104D03*
X1256435Y54843D03*
X1259387Y49331D03*
Y64292D03*
X1256435Y69803D03*
X1268246Y79252D03*
X1277104D03*
X1274151Y84764D03*
X1265293D03*
Y99725D03*
X1274151D03*
X1268246Y94213D03*
X1277104D03*
X1259387Y79252D03*
Y94213D03*
X1256435Y84764D03*
Y99725D03*
G54D26*
X108200Y775800D03*
X112700Y775300D03*
Y770800D03*
X108200D03*
X103700D03*
Y775800D03*
Y766300D03*
X108200D03*
X112700D03*
X223000Y184000D03*
Y188500D03*
X225000Y192500D03*
X229200D03*
X243000Y176500D03*
X243500Y166500D03*
Y162000D03*
Y157000D03*
X243000Y181000D03*
Y186000D03*
X239900Y600100D03*
X240000Y608600D03*
Y604400D03*
X536081Y304376D03*
X536809Y298789D03*
X553563Y306108D03*
Y310608D03*
X557904Y327115D03*
X562123Y319158D03*
X553455Y314807D03*
X553463Y319108D03*
X557863D03*
X585515Y276459D03*
X583009Y264117D03*
X585351Y269292D03*
X587984Y246148D03*
X587980Y251975D03*
X589164Y264150D03*
X582738Y273300D03*
X587063Y257608D03*
X582976Y246148D03*
X583286Y251974D03*
X582682Y257614D03*
X589400Y308626D03*
X585737Y289608D03*
Y283108D03*
X582683Y279618D03*
X582411Y286589D03*
X582363Y293408D03*
X580563Y308608D03*
X583391Y298870D03*
X583282Y303091D03*
X670063Y274708D03*
X669633Y259148D03*
X704537Y221492D03*
X689623Y269648D03*
X694963Y269608D03*
X689723Y274748D03*
X694223D03*
X679723D03*
X684223D03*
X690233Y255748D03*
X695000Y255800D03*
X690133Y260348D03*
X694633D03*
X680133Y259148D03*
X684633D03*
X674563Y274708D03*
X674133Y259148D03*
X695963Y302308D03*
Y297808D03*
Y293308D03*
X690663Y287608D03*
Y292108D03*
X712337Y207792D03*
X712137Y213292D03*
Y219392D03*
X738800Y272000D03*
Y265500D03*
Y258000D03*
Y251500D03*
X706800Y272500D03*
Y265500D03*
Y258000D03*
Y252000D03*
X715300Y272000D03*
Y265500D03*
Y258000D03*
Y251500D03*
X724300Y272000D03*
Y265500D03*
Y258000D03*
Y251500D03*
X732300Y272000D03*
Y265500D03*
Y258000D03*
Y251500D03*
X921300Y74700D03*
X918100Y71900D03*
X929464Y49420D03*
X925022Y42909D03*
X929713Y44849D03*
X985880Y41686D03*
Y46086D03*
Y50586D03*
X1177600Y241200D03*
X1173400D03*
X1166400Y234300D03*
X1170600D03*
X1175700D03*
X1177200Y248200D03*
X1173000D03*
X1177300Y254400D03*
X1173100D03*
X1176300Y261500D03*
X1171200D03*
X1167000D03*
X1203100Y241100D03*
X1198900D03*
X1207900D03*
X1182400Y241200D03*
X1197900Y234300D03*
X1207400D03*
X1203200D03*
X1179900D03*
X1188900D03*
X1184700D03*
X1193700D03*
X1182000Y248200D03*
X1202600Y254100D03*
X1198400D03*
X1207400D03*
X1202500Y247500D03*
X1198300D03*
X1207300D03*
X1182100Y254400D03*
X1203800Y261500D03*
X1208000D03*
X1194300D03*
X1198500D03*
X1185300D03*
X1189500D03*
X1180500D03*
X1212900Y234300D03*
X1233900Y240700D03*
X1239900D03*
X1244900D03*
X1228900D03*
X1228500Y235000D03*
X1234000D03*
X1240000D03*
X1245000D03*
X1214000Y261500D03*
X1233800Y246600D03*
X1239800D03*
X1244800D03*
X1228800D03*
X1229000Y252000D03*
X1245000D03*
X1240000D03*
X1234000D03*
X1255900Y240700D03*
X1249900D03*
X1262500Y235000D03*
X1250000D03*
X1256000D03*
X1255800Y246600D03*
X1249800D03*
X1262000Y252000D03*
X1256000D03*
X1250000D03*
X1360844Y210366D03*
X1355944Y210313D03*
X1351525Y207104D03*
X1351545Y202879D03*
Y198575D03*
X1378115Y189144D03*
X1374000Y192500D03*
Y188300D03*
Y196700D03*
X1378500Y198000D03*
X1378115Y193344D03*
X1351777Y227823D03*
X1360644Y223881D03*
X1350987Y236754D03*
X1351668Y232125D03*
X1355644Y223881D03*
X1351899Y219598D03*
X1351954Y215268D03*
X1354989Y239016D03*
X1350950Y241000D03*
X1349639Y211374D03*
X1349298Y223737D03*
X1355050Y247300D03*
X1350950Y246100D03*
X1382500Y193500D03*
Y188000D03*
G54D38*
X943111Y5908D03*
X935236D03*
X927361D03*
X919486D03*
X911616D03*
X943111Y13778D03*
X935236D03*
X927361D03*
X919486D03*
X958856Y5908D03*
X950986D03*
X958856Y13778D03*
X950986D03*
G54D18*
X41603Y177598D03*
X65579D03*
X57587D03*
X49595D03*
X45559Y187598D03*
X37567D03*
X53551D03*
X73571Y177598D03*
X81563D03*
X77607Y187598D03*
X69615D03*
X85599D03*
G54D25*
X122700Y476100D03*
Y478400D03*
X122600Y473800D03*
Y471500D03*
X121673Y491672D03*
X130985Y504300D03*
X124822Y504271D03*
X127973Y504272D03*
X121673Y497973D03*
Y494822D03*
X118500Y504238D03*
X115373Y504271D03*
X127973Y510571D03*
X124823D03*
X121673D03*
X131121Y513721D03*
X121673D03*
X131121Y510570D03*
X127971Y513721D03*
X124821D03*
X127971Y494823D03*
X131122Y491674D03*
X127973Y488524D03*
X131122D03*
Y485374D03*
X121673Y504272D03*
X124823Y501122D03*
X121673D03*
X127973Y497973D03*
X124822Y488523D03*
X127973Y491674D03*
X124823Y497973D03*
Y491674D03*
X127973Y485374D03*
X124823Y494822D03*
X131121Y494823D03*
X127973Y501122D03*
Y529469D03*
X124823Y523170D03*
Y532617D03*
X124822Y545216D03*
X131122Y532618D03*
X124823Y535766D03*
X127973Y538918D03*
X127996Y535781D03*
X121673Y545215D03*
Y523170D03*
X131121Y529467D03*
Y520018D03*
X127971D03*
X131121Y523168D03*
X124822Y520019D03*
X121673Y520020D03*
X115374Y529467D03*
X118524D03*
X121673D03*
X124823D03*
X121673Y532617D03*
X124822Y538917D03*
X121673Y535766D03*
X127973Y523170D03*
X121673Y538916D03*
X126801Y574386D03*
X124900Y559638D03*
X124847Y550110D03*
X124900Y556462D03*
Y565990D03*
Y562814D03*
Y553286D03*
X122547Y561276D03*
Y554924D03*
Y567628D03*
X125072Y610945D03*
X125070Y598347D03*
X131370Y601496D03*
X118773Y601495D03*
X126646Y606400D03*
X115622Y614094D03*
Y601496D03*
X121922Y610945D03*
X128220Y614095D03*
X118773Y604645D03*
X125070Y614095D03*
X118773Y598345D03*
X118805Y614099D03*
X115623Y598345D03*
X118773Y610945D03*
X131369Y614095D03*
X118773Y589748D03*
X128221Y610945D03*
X121922Y588872D03*
X118773Y592048D03*
X125072Y620392D03*
X121921D03*
X140571Y491674D03*
X140570Y488523D03*
X162618Y485374D03*
X150020Y491674D03*
X156319Y485374D03*
X143721Y491674D03*
Y488524D03*
Y485374D03*
X140569Y494823D03*
X134270Y510571D03*
Y504272D03*
X146869Y494823D03*
X153168D03*
X159467D03*
X165768Y488524D03*
X153170Y491674D03*
X150020Y485374D03*
Y482225D03*
X146870Y485374D03*
Y488524D03*
X162618D03*
Y491674D03*
X134272D03*
X165768D03*
X134272Y488524D03*
Y485374D03*
X137421Y491674D03*
Y485374D03*
X140571D03*
X156318Y488523D03*
X156319Y491674D03*
X153169Y485374D03*
Y488524D03*
X159469Y491674D03*
Y488524D03*
Y485374D03*
X150020Y488524D03*
X137421D03*
X165766Y542066D03*
X143721Y532618D03*
X137421Y535768D03*
Y542066D03*
X134270Y538916D03*
X137421Y532618D03*
X134272Y542066D03*
Y535768D03*
X140570Y535767D03*
X137421Y538918D03*
X153188Y538899D03*
X162617Y535766D03*
X146869Y538954D03*
X146858Y535742D03*
X159449Y542048D03*
Y538898D03*
X159456Y532642D03*
X162617Y542066D03*
Y538916D03*
X149981Y538917D03*
X153132Y535767D03*
X149985Y535771D03*
X153194Y542078D03*
X153187Y532636D03*
X140571Y532618D03*
X143718Y538953D03*
X143686Y542070D03*
X146869Y529469D03*
X134270Y523170D03*
X153168Y529469D03*
X140569D03*
X134270Y516869D03*
X159467Y529469D03*
X134272Y532618D03*
X162618D03*
X165766Y538916D03*
X161280Y564000D03*
X147451Y551836D03*
Y549536D03*
X142951Y551036D03*
X161280Y566300D03*
X159537Y548256D03*
X147451Y556436D03*
X142951Y555636D03*
X160700Y551356D03*
X151989Y557138D03*
X161280Y556100D03*
X151989Y554838D03*
X161280Y558400D03*
X137669Y610945D03*
Y601495D03*
X140818D03*
X134521Y595196D03*
X134519Y614095D03*
X150269Y598347D03*
X156566Y614095D03*
X143968Y601495D03*
X140821Y614106D03*
X166016Y601496D03*
X159716Y610945D03*
Y614095D03*
Y595197D03*
X166016Y610944D03*
X162867Y614095D03*
X147115Y598360D03*
X150268Y601496D03*
X147141Y614096D03*
X143968Y588898D03*
X153417Y610945D03*
X159716Y604645D03*
X166015Y598345D03*
X147117Y610945D03*
X162865Y601495D03*
X150268Y610944D03*
X159716Y601495D03*
X140818Y610945D03*
X134520Y610944D03*
X153418Y592048D03*
X159716D03*
X134521Y598345D03*
X143968Y592048D03*
X147117Y601495D03*
X150251Y617226D03*
X134521Y617266D03*
X137671D03*
X140821D03*
X156566Y617244D03*
X159716D03*
X150351Y620436D03*
X181514Y479075D03*
X172065Y513721D03*
X175215D03*
X178365Y510571D03*
X175215D03*
X172065D03*
Y501122D03*
X178365Y507422D03*
X175215D03*
Y491674D03*
Y497973D03*
X172065Y491674D03*
X175215Y485374D03*
X175217Y482225D03*
X175215Y501122D03*
X178365D03*
X184664Y485372D03*
X172065Y494823D03*
X178365Y491674D03*
X181514Y488524D03*
X184664Y488522D03*
X175215Y494823D03*
X172065Y497973D03*
X178365Y494823D03*
X172065Y485374D03*
X172067Y482225D03*
X178365Y497973D03*
X172065Y504272D03*
X175216Y504271D03*
X172065Y507422D03*
X178365Y504272D03*
X168916Y510571D03*
Y504272D03*
X178365Y513721D03*
X172065Y488524D03*
X175216Y488523D03*
X178365Y485374D03*
Y488524D03*
X181514Y485374D03*
X178365Y520020D03*
X181514D03*
X172065Y535768D03*
Y526319D03*
X178365Y529469D03*
X175215D03*
X172065D03*
X175215Y523170D03*
X178365D03*
X175216Y535767D03*
X168916Y523170D03*
Y516870D03*
X184665Y520019D03*
X178365Y526319D03*
X175215D03*
Y532618D03*
X178365Y535768D03*
X172065Y532618D03*
X175215Y538918D03*
X168916Y535766D03*
X172065Y538918D03*
X168916Y542066D03*
Y538916D03*
X178365Y532618D03*
X874410Y139764D03*
Y131890D03*
Y120079D03*
Y124016D03*
Y155512D03*
Y147638D03*
Y206692D03*
Y194881D03*
Y183071D03*
Y230314D03*
Y222440D03*
Y214566D03*
X894095Y131890D03*
X898032Y139764D03*
Y131890D03*
Y135827D03*
X905906Y127953D03*
X901969Y139764D03*
Y135827D03*
Y131890D03*
X886221Y139764D03*
X890158Y135827D03*
X886221Y131890D03*
X890158Y139764D03*
X894095Y135827D03*
X890158Y131890D03*
X878347Y135827D03*
Y116142D03*
X882284Y120079D03*
X886221Y116142D03*
X890158Y120079D03*
X894095Y116142D03*
X898032Y120079D03*
X901969Y116142D03*
X878347Y139764D03*
X882284Y135827D03*
X878347Y131890D03*
Y120079D03*
X882300Y124032D03*
X886221Y120079D03*
X890158Y124016D03*
X894095Y120079D03*
X898032Y124016D03*
X901969Y120079D03*
X905906Y139764D03*
Y135827D03*
Y131890D03*
X894095Y163386D03*
X898032D03*
Y167323D03*
Y171260D03*
Y175197D03*
X901969Y163386D03*
X905906D03*
X898032Y143701D03*
Y147638D03*
Y151575D03*
Y155512D03*
Y159449D03*
X901969Y147638D03*
Y143701D03*
X890158Y159449D03*
X886221Y155512D03*
X890158Y151575D03*
X886221Y147638D03*
X890158Y143701D03*
X894095Y159449D03*
X890158Y155512D03*
X894095Y151575D03*
X890158Y147638D03*
X894095Y143701D03*
X878347Y159449D03*
Y151575D03*
Y143701D03*
X882284Y159449D03*
X878347Y155512D03*
X882284Y151575D03*
X878347Y147638D03*
X882284Y143701D03*
X905906Y155512D03*
Y151575D03*
Y147638D03*
Y143701D03*
X901969Y155512D03*
Y151575D03*
X898032Y194881D03*
Y198818D03*
Y202755D03*
X894095D03*
X898032Y179134D03*
Y183071D03*
Y190944D03*
X905906Y183071D03*
X901969D03*
X886221Y206692D03*
X890158Y198818D03*
X886221Y194881D03*
X890158Y190944D03*
X886221Y183071D03*
X890158Y179134D03*
Y206692D03*
X894095Y198818D03*
X890158Y194881D03*
X894095Y190944D03*
X890158Y183071D03*
X894095Y179134D03*
X878347Y198818D03*
Y190944D03*
Y206692D03*
X882284Y198818D03*
X878347Y194881D03*
X882284Y190944D03*
X878347Y183071D03*
X898032Y238188D03*
X894095D03*
X898032Y234251D03*
Y230314D03*
X905906Y238188D03*
X901969D03*
X898032Y226377D03*
Y222440D03*
Y218503D03*
Y214566D03*
Y210629D03*
X890158Y234251D03*
X886221Y230314D03*
X890158Y226377D03*
X886221Y222440D03*
X890158Y218503D03*
X886221Y214566D03*
X890158Y210629D03*
X905906Y242125D03*
X898032D03*
X890158D03*
X882284D03*
X894095Y234251D03*
X890158Y230314D03*
X894095Y226377D03*
X890158Y222440D03*
X894095Y218503D03*
X890158Y214566D03*
X894095Y210629D03*
X878347Y234251D03*
Y226377D03*
Y218503D03*
Y210629D03*
X882284Y234251D03*
X878347Y230314D03*
X882284Y226377D03*
X878347Y222440D03*
X882284Y218503D03*
X878347Y214566D03*
X882284Y210629D03*
X905906Y246062D03*
X901969Y249999D03*
X898032Y246062D03*
X894095Y249999D03*
X890158Y246062D03*
X886221Y249999D03*
X882284Y246062D03*
X878347Y249999D03*
X901969Y246062D03*
X894095D03*
X886221D03*
X878347D03*
X905906Y257873D03*
X901969Y261810D03*
X898032Y257873D03*
X894095Y261810D03*
X890158Y257873D03*
X886221Y261810D03*
X882284Y257873D03*
X878347Y261810D03*
X905906Y253936D03*
X901969Y257873D03*
X898032Y253936D03*
X894095Y257873D03*
X890158Y253936D03*
X886221Y257873D03*
X882284Y253936D03*
X878347Y257873D03*
X909843Y131890D03*
X941339Y127953D03*
X913780Y131890D03*
Y127953D03*
Y139764D03*
X921654Y127953D03*
X929528D03*
X937402Y139764D03*
Y127953D03*
X921654Y139764D03*
X929528D03*
X925591D03*
X921654Y131890D03*
X941339D03*
Y135827D03*
X933465Y131890D03*
Y135827D03*
X937402Y131890D03*
Y135827D03*
X929528Y131890D03*
Y135827D03*
X925591Y131890D03*
Y135827D03*
X909843Y120079D03*
X913780Y116142D03*
X917717Y120079D03*
X921654Y116142D03*
X925591Y120079D03*
X929528Y116142D03*
X933465Y120079D03*
X937402Y116142D03*
X909843Y124016D03*
X913780Y120079D03*
X917717Y124016D03*
X921654Y120079D03*
X925591Y124016D03*
X929528Y120079D03*
X933465Y124016D03*
X937402Y120079D03*
X913780Y135827D03*
X917717Y139764D03*
Y131890D03*
Y135827D03*
X909843Y139764D03*
X937402Y155512D03*
X941339Y151575D03*
Y155512D03*
X929528Y159449D03*
X913780Y143701D03*
Y159449D03*
X937402Y175197D03*
X941339Y171260D03*
X937402Y167323D03*
X941339Y163386D03*
X929528Y175197D03*
X933465Y171260D03*
X929528Y167323D03*
X933465Y163386D03*
X925591Y171260D03*
X921654Y175197D03*
X925591Y163386D03*
X921654Y167323D03*
X917717Y163386D03*
Y171260D03*
X921654Y159449D03*
X937402D03*
X925591Y151575D03*
X913780Y147638D03*
X917717Y159449D03*
X913780Y155512D03*
Y151575D03*
X933465D03*
Y155512D03*
X921654Y151575D03*
X929528D03*
Y155512D03*
X925591Y143701D03*
Y147638D03*
Y155512D03*
X909843Y159449D03*
Y143701D03*
Y155512D03*
X941339Y143701D03*
Y147638D03*
X933465Y143701D03*
Y147638D03*
X937402Y143701D03*
Y147638D03*
X929528Y143701D03*
Y147638D03*
X917717Y155512D03*
Y151575D03*
Y143701D03*
Y147638D03*
X921654Y155512D03*
X917717Y179134D03*
X913780Y183071D03*
X921654Y194881D03*
X917717Y198818D03*
X937402Y194881D03*
X933465Y198818D03*
X929528Y202755D03*
X925591Y206692D03*
X929528Y194881D03*
X925591Y198818D03*
X921654Y202755D03*
X917717Y206692D03*
X933465D03*
X937402Y202755D03*
X941339Y198818D03*
Y206692D03*
X925591Y190944D03*
X933465Y179134D03*
X929528Y183071D03*
X925591Y179134D03*
X921654Y183071D03*
X941339Y190944D03*
X933465D03*
X937402Y183071D03*
X941339Y179134D03*
X917717Y190944D03*
X921654Y238188D03*
X917717D03*
Y214566D03*
X913780Y238188D03*
X909843D03*
X913780Y214566D03*
X941339Y226377D03*
X937402Y222440D03*
X933465Y226377D03*
X929528Y222440D03*
X925591Y226377D03*
X929528Y230314D03*
X937402D03*
X941339Y234251D03*
X937402Y238188D03*
X933465Y234251D03*
X929528Y238188D03*
X925591Y234251D03*
X921654Y210629D03*
X925591Y214566D03*
X929528Y210629D03*
X941339Y214566D03*
X933465D03*
X937402Y210629D03*
X941339Y242125D03*
X933465D03*
X925591D03*
X917717D03*
X941339Y246062D03*
X937402Y249999D03*
X933465Y246062D03*
X929528Y249999D03*
X925591Y246062D03*
X921654Y249999D03*
X917717Y246062D03*
X913780Y249999D03*
X937402Y246062D03*
X929528D03*
X921654D03*
X913780D03*
X941339Y257873D03*
X937402Y261810D03*
X933465Y257873D03*
X929528Y261810D03*
X925591Y257873D03*
X921654Y261810D03*
X917717Y257873D03*
X913780Y261810D03*
X941339Y253936D03*
X937402Y257873D03*
X933465Y253936D03*
X929528Y257873D03*
X925591Y253936D03*
X921654Y257873D03*
X917717Y253936D03*
X913780Y257873D03*
X953149Y127953D03*
X949212D03*
Y139764D03*
X957086Y127953D03*
X964960D03*
X972834D03*
X957086Y139764D03*
X972834D03*
X953149D03*
Y131890D03*
X957086D03*
X964960D03*
X961023Y139764D03*
Y131890D03*
Y135827D03*
X957086D03*
Y116142D03*
X961023Y120079D03*
X964960Y116142D03*
X968897Y120079D03*
X972834Y116142D03*
X957086Y120079D03*
X961023Y124016D03*
X964960Y120079D03*
X968897Y124016D03*
X972834Y120079D03*
Y135827D03*
Y131890D03*
X964960Y135827D03*
Y139764D03*
X968897Y135827D03*
Y131890D03*
X949212Y155512D03*
X953149Y163386D03*
X949212Y167323D03*
X964960D03*
X968897Y163386D03*
X957086Y175197D03*
X961023Y171260D03*
X953149D03*
X949212Y175197D03*
X961023Y163386D03*
X957086Y167323D03*
X972834D03*
X968897Y171260D03*
X964960Y175197D03*
X972834D03*
X968897Y151575D03*
X964960Y159449D03*
X957086D03*
X953149Y151575D03*
X949212Y159449D03*
X972834D03*
Y151575D03*
X957086Y143701D03*
X961023D03*
X957086Y151575D03*
Y147638D03*
Y155512D03*
X953149Y143701D03*
Y155512D03*
X949212Y143701D03*
Y147638D03*
X964960Y143701D03*
X961023Y155512D03*
Y151575D03*
X964960Y155512D03*
Y151575D03*
X968897Y155512D03*
X964960Y147638D03*
X968897D03*
Y143701D03*
X972834D03*
Y155512D03*
X949212Y194881D03*
X968897Y198818D03*
X964960Y202755D03*
X961023Y206692D03*
X972834Y194881D03*
X953149Y206692D03*
X964960Y194881D03*
X961023Y198818D03*
X957086Y202755D03*
X949212D03*
X953149Y198818D03*
X957086Y194881D03*
X972834Y202755D03*
X968897Y206692D03*
X949212Y183071D03*
X953149Y179134D03*
X961023D03*
X957086Y183071D03*
X953149Y190944D03*
X968897D03*
X972834Y183071D03*
X961023Y190944D03*
X964960Y183071D03*
X968897Y179134D03*
X972834Y238188D03*
X968897Y226377D03*
Y234251D03*
X953149Y226377D03*
X949212Y222440D03*
Y230314D03*
X964960Y222440D03*
X961023Y226377D03*
X957086Y222440D03*
X964960Y230314D03*
X957086D03*
X953149Y234251D03*
X949212Y238188D03*
X964960D03*
X961023Y234251D03*
X957086Y238188D03*
X953149Y214566D03*
X957086Y210629D03*
X949212D03*
X972834D03*
X968897Y214566D03*
X961023D03*
X964960Y210629D03*
X968897Y242125D03*
X961023D03*
X953149D03*
X972834Y249999D03*
X968897Y246062D03*
X964960Y249999D03*
X961023Y246062D03*
X957086Y249999D03*
X953149Y246062D03*
X972834D03*
X964960D03*
X957086D03*
X972834Y261810D03*
X968897Y257873D03*
X964960Y261810D03*
X961023Y257873D03*
X957086Y261810D03*
X953149Y257873D03*
X972834D03*
X968897Y253936D03*
X964960Y257873D03*
X961023Y253936D03*
X957086Y257873D03*
X953149Y253936D03*
X992519Y139764D03*
X996456D03*
Y131890D03*
Y135827D03*
X1000393Y131890D03*
X980708Y127953D03*
Y139764D03*
Y135827D03*
Y131890D03*
X1008267Y139764D03*
X976771Y120079D03*
X980708Y116142D03*
X984645Y120079D03*
X1008267Y131890D03*
X1004330Y135827D03*
Y139764D03*
X976771Y124016D03*
X980708Y120079D03*
X984645Y124016D03*
X1004330Y131890D03*
X1000393Y135827D03*
X992519Y115742D03*
X996456Y120079D03*
X1000393Y116142D03*
X1004330Y120079D03*
X1008267Y116142D03*
X992519Y120079D03*
X996456Y124016D03*
X1000393Y120079D03*
X1004330Y124016D03*
X1008267Y120079D03*
X988582Y139764D03*
Y135827D03*
X984645Y131890D03*
X976771D03*
Y139764D03*
X988582Y131890D03*
X984645Y139764D03*
X976771Y135827D03*
X996456Y163386D03*
X1000393D03*
X996456Y167323D03*
Y171260D03*
Y175197D03*
X992519Y163386D03*
X988582D03*
X980708Y175197D03*
X996456Y143701D03*
Y147638D03*
Y151575D03*
Y155512D03*
Y159449D03*
X976771Y163386D03*
Y171260D03*
X980708Y159449D03*
Y155512D03*
X976771Y151575D03*
X1004330Y143701D03*
X1008267Y147638D03*
X1004330Y151575D03*
X1008267Y155512D03*
X1004330Y159449D03*
X1008267Y167323D03*
X1004330Y171260D03*
X1008267Y175197D03*
X1000393Y143701D03*
X1004330Y147638D03*
X1000393Y151575D03*
X1004330Y155512D03*
X1000393Y159449D03*
X1004330Y167323D03*
X1000393Y171260D03*
X1004330Y175197D03*
X988582Y147638D03*
Y143701D03*
X984645Y155512D03*
Y151575D03*
Y143701D03*
X988582Y151575D03*
X976771Y147638D03*
X980708Y143701D03*
X976771Y155512D03*
X980708Y147638D03*
Y151575D03*
X976771Y159449D03*
Y143701D03*
X996456Y194881D03*
Y198818D03*
Y202755D03*
X1000393D03*
X996456Y179134D03*
Y183071D03*
Y190944D03*
X992519Y183071D03*
X988582D03*
X976771Y179134D03*
X980708Y183071D03*
X976771Y206692D03*
Y198818D03*
Y190944D03*
X1004330Y179134D03*
X1008267Y183071D03*
X1004330Y190944D03*
X1008267Y194881D03*
X1004330Y198818D03*
X1008267Y206692D03*
X1000393Y179134D03*
X1004330Y183071D03*
X1000393Y190944D03*
X1004330Y194881D03*
X1000393Y198818D03*
X1004330Y206692D03*
X992519Y238188D03*
X988582D03*
X984645D03*
X980708D03*
X1000393D03*
X996456D03*
Y234251D03*
Y230314D03*
Y226377D03*
Y222440D03*
Y218503D03*
Y214566D03*
Y210629D03*
X976771Y238188D03*
Y214566D03*
X980708D03*
X1004330Y210629D03*
X1008267Y214566D03*
X1004330Y218503D03*
X1008267Y222440D03*
X1004330Y226377D03*
X1008267Y230314D03*
X1004330Y234251D03*
X1000393Y210629D03*
X1004330Y214566D03*
X1000393Y218503D03*
X1004330Y222440D03*
X1000393Y226377D03*
X1004330Y230314D03*
X1000393Y234251D03*
X1004330Y242125D03*
X996456D03*
X988582D03*
X976771D03*
X1008267Y249999D03*
X1004330Y246062D03*
X1000393Y249999D03*
X996456Y246062D03*
X992519Y249999D03*
X988582Y246062D03*
X980708Y249999D03*
X976771Y246062D03*
X1008267D03*
X1000393D03*
X992519D03*
X980708D03*
X1008267Y261810D03*
X1004330Y257873D03*
X1000393Y261810D03*
X996456Y257873D03*
X992519Y261810D03*
X988582Y257873D03*
X980708Y261810D03*
X976771Y257873D03*
X1008267D03*
X1004330Y253936D03*
X1000393Y257873D03*
X996456Y253936D03*
X992519Y257873D03*
X988582Y253936D03*
X980708Y257873D03*
X976771Y253936D03*
X1020078Y139764D03*
X1012204Y120079D03*
X1016141Y116142D03*
X1020078Y120079D03*
Y131890D03*
X1016141Y135827D03*
Y139764D03*
X1012204Y124016D03*
X1016141Y120079D03*
X1023278D03*
X1016141Y131890D03*
X1012204Y135827D03*
X1016141Y143701D03*
X1020078Y147638D03*
X1016141Y151575D03*
X1020078Y155512D03*
X1016141Y159449D03*
X1020078Y167323D03*
X1016141Y171260D03*
X1020078Y175197D03*
X1012204Y143701D03*
X1016141Y147638D03*
X1012204Y151575D03*
X1016141Y155512D03*
X1012204Y159449D03*
X1016141Y167323D03*
X1012204Y171260D03*
X1016141Y175197D03*
Y179134D03*
X1020078Y183071D03*
X1016141Y190944D03*
X1020078Y194881D03*
X1016141Y198818D03*
X1020078Y206692D03*
X1012204Y179134D03*
X1016141Y183071D03*
X1012204Y190944D03*
X1016141Y194881D03*
X1012204Y198818D03*
X1016141Y206692D03*
X1012204Y242125D03*
X1016141Y210629D03*
X1020078Y214566D03*
X1016141Y218503D03*
X1020078Y222440D03*
X1016141Y226377D03*
X1020078Y230314D03*
X1016141Y234251D03*
X1012204Y210629D03*
X1016141Y214566D03*
X1012204Y218503D03*
X1016141Y222440D03*
X1012204Y226377D03*
X1016141Y230314D03*
X1012204Y234251D03*
X1016141Y249999D03*
X1012204Y246062D03*
X1016141D03*
Y261810D03*
X1012204Y257873D03*
X1016141D03*
X1012204Y253936D03*
G54D23*
X134251Y153543D03*
X151968D03*
X144094D03*
X1027722Y-9125D03*
X1054494D03*
G54D31*
X476614Y167493D03*
Y162493D03*
Y157493D03*
G54D28*
X193900Y274372D03*
X183900D03*
X203900D03*
X302500Y207200D03*
X292500D03*
X326200D03*
X336200D03*
X312500D03*
X346200D03*
X465485Y200680D03*
Y190680D03*
Y180680D03*
X488462Y180761D03*
Y190761D03*
Y200761D03*
X526215Y184000D03*
X511742Y215594D03*
X521742D03*
X531742D03*
X565585Y184000D03*
X772300Y16200D03*
X762300D03*
X752300D03*
X785300Y16100D03*
X795300D03*
X805300D03*
X1348785Y161642D03*
X1323195D03*
G54D12*
X31977Y126614D03*
Y116614D03*
X91189Y126614D03*
Y116614D03*
Y136614D03*
G54D34*
X487404Y255245D03*
G54D20*
X58400Y271800D03*
X57500Y263300D03*
X63700Y257300D03*
X63800Y267100D03*
X44426Y267408D03*
X59173Y288186D03*
X71094Y285981D03*
X77964Y285670D03*
X68429Y288212D03*
X75450Y694150D03*
X130900Y714300D03*
Y710800D03*
X107950Y687650D03*
X111400Y741800D03*
Y718300D03*
X118060Y743460D03*
X136400Y738300D03*
Y721800D03*
X623498Y140671D03*
X886221Y171260D03*
G54D11*
X18577Y107902D03*
X5500Y119571D03*
Y139571D03*
Y159571D03*
X22000Y167200D03*
X5500Y179571D03*
Y199571D03*
X26500Y199500D03*
X21900Y199700D03*
X21800Y188100D03*
X5500Y219571D03*
Y239571D03*
X23100Y224500D03*
X28400Y262800D03*
X18000Y271600D03*
X5500Y259571D03*
X18000Y289400D03*
X28200Y296100D03*
X5500Y279571D03*
Y299571D03*
X26300Y317600D03*
X21400Y327900D03*
Y341000D03*
X5500Y339571D03*
Y319571D03*
X21400Y354000D03*
X22900Y365300D03*
X5500Y359571D03*
Y399571D03*
Y379571D03*
X31324Y410800D03*
X5500Y419571D03*
Y439571D03*
Y479571D03*
Y459571D03*
Y499571D03*
Y519571D03*
Y539571D03*
Y579571D03*
Y559571D03*
Y599571D03*
Y639571D03*
Y619571D03*
Y679571D03*
Y659571D03*
Y699571D03*
X27125Y695275D03*
X18250Y749250D03*
X5500Y719571D03*
Y739571D03*
Y779571D03*
Y759571D03*
Y799571D03*
X10020Y835051D03*
X30020D03*
X5500Y819571D03*
X31400Y209190D03*
X46760Y209157D03*
X63250Y205050D03*
X42800Y200100D03*
X44400Y216600D03*
X34900Y216800D03*
X59800Y211800D03*
X50200Y212000D03*
X31500Y224400D03*
X44029Y272572D03*
X35150Y273250D03*
X42900Y284500D03*
X58730Y299508D03*
X35150Y284350D03*
X49100Y328300D03*
X39600Y317600D03*
X58990Y342700D03*
X34800Y321200D03*
X54600Y328600D03*
X31500Y366900D03*
X48512Y356488D03*
X49300Y346700D03*
X43262Y357062D03*
X44866Y378634D03*
X55907Y350673D03*
X60610Y381665D03*
X47132Y444399D03*
X48000Y426000D03*
Y422500D03*
Y429500D03*
X57800Y420700D03*
X31500Y447000D03*
X64200Y534500D03*
X53500Y690200D03*
X60650Y694050D03*
X50020Y835051D03*
X96584Y195100D03*
X78050Y196300D03*
X82676Y208785D03*
X67600Y209500D03*
X92859Y226659D03*
X87978Y226596D03*
X78508Y232693D03*
X72934Y232675D03*
X95200Y210800D03*
X85600D03*
X80600Y216700D03*
X71000Y216600D03*
X88276Y232700D03*
X94600Y277100D03*
X93672Y270153D03*
X71870Y257120D03*
X75400Y309700D03*
X78121Y325870D03*
X73721D03*
X70210Y342700D03*
X77290Y344212D03*
X86511Y344200D03*
X66400Y334500D03*
X75256Y370303D03*
X70591Y359309D03*
X71794Y377639D03*
X92580Y410761D03*
X79600Y399200D03*
X95223Y385704D03*
X92752Y434193D03*
X91370Y445394D03*
X70700Y443244D03*
X77859Y429879D03*
X72533Y416996D03*
X79164Y426221D03*
X91311Y456609D03*
X89400Y470400D03*
X77681Y499033D03*
X77413Y506468D03*
X90500Y580100D03*
X81000Y579000D03*
X95252Y571638D03*
X70800Y559895D03*
X77400Y559000D03*
X77250Y562750D03*
X77400Y577000D03*
X71400Y578300D03*
X87555Y561085D03*
X87200Y574250D03*
X90500Y587000D03*
X80300Y596100D03*
X69258Y603000D03*
X82000Y592500D03*
X78300Y634250D03*
X94860Y628750D03*
X75800Y681900D03*
X69700Y690300D03*
X89825Y692875D03*
X79250Y716050D03*
X91800Y716100D03*
X66700Y713500D03*
X70020Y835051D03*
X90020D03*
X118577Y107902D03*
X104000Y128330D03*
X114364Y122054D03*
X118500Y176500D03*
Y173000D03*
X100900Y173800D03*
X116000Y207000D03*
Y202000D03*
X118500Y188500D03*
X116000Y192000D03*
Y196500D03*
X118500Y185000D03*
Y181000D03*
X104100Y194600D03*
X103700Y200800D03*
X116000Y211500D03*
X113300Y276600D03*
X127330Y248029D03*
X112764Y264218D03*
X109810Y310358D03*
X113000Y280500D03*
X113100Y284100D03*
X109972Y305968D03*
X112217Y296435D03*
X106400Y312200D03*
X99128Y366961D03*
X108200Y378656D03*
X126800Y362500D03*
X108484Y348377D03*
X108453Y385164D03*
X100924Y409968D03*
X105303Y419497D03*
X116173Y422379D03*
X107844Y414785D03*
X99749Y443671D03*
X99818Y437908D03*
X127925Y428093D03*
X115500Y454700D03*
X111500D03*
X103500D03*
X118524Y491672D03*
X124823Y542067D03*
X127973Y532618D03*
Y542067D03*
X104461Y571715D03*
X100140Y559260D03*
X99460Y566200D03*
X126869Y577770D03*
X122547Y564452D03*
Y558100D03*
Y551748D03*
X121601Y574686D03*
X104400Y590300D03*
X131369Y610945D03*
X115622Y604646D03*
X121911Y614076D03*
X102000Y599000D03*
X131369Y588898D03*
X121922Y592048D03*
X118771Y595196D03*
X121922Y617244D03*
X128221D03*
X120351Y633500D03*
X126851Y633449D03*
X116551Y644936D03*
X131369Y617244D03*
X118771D03*
X125070D03*
X131051Y656436D03*
X119051Y653906D03*
X109800Y681900D03*
X132200Y761300D03*
Y756300D03*
X138577Y107902D03*
X158577D03*
X149380Y176010D03*
X163000Y211500D03*
X157200Y241400D03*
X153000Y225000D03*
X134120Y267630D03*
X157300Y259900D03*
X157400Y254000D03*
X157300Y246500D03*
X139286Y311214D03*
X158170Y314302D03*
X162670D03*
X153670D03*
X156170Y318302D03*
X160670D03*
X143000Y342900D03*
X155891Y339730D03*
X140500Y390500D03*
X145500Y385500D03*
X158800Y406255D03*
X143000Y388000D03*
X142608Y403594D03*
X157550Y399100D03*
X139019Y443177D03*
X159540Y445692D03*
X146165Y444876D03*
X149838Y446190D03*
X150431Y420306D03*
X133000Y454700D03*
X146870Y491674D03*
Y482225D03*
X150020Y510571D03*
X153169D03*
X146870D03*
X153169Y513721D03*
X146870D03*
X150020D03*
X146870Y516870D03*
X150020D03*
X153169D03*
X151989Y552538D03*
X147451Y554136D03*
X142951Y553336D03*
X161280Y553800D03*
Y561700D03*
X143968Y614095D03*
X143967Y610945D03*
X137669Y604645D03*
X162865Y595196D03*
Y604645D03*
X156566Y610945D03*
X159716Y598345D03*
X153417Y614095D03*
X150269D03*
X153418Y595197D03*
X162865Y610945D03*
X137661Y614096D03*
X137670Y595197D03*
X147143Y595184D03*
X165851Y630651D03*
X137551Y629849D03*
X149851Y631251D03*
X155851Y631051D03*
X160851Y630651D03*
X150069Y640500D03*
X150280Y636620D03*
X150600Y648300D03*
X150409Y643884D03*
X143969Y617244D03*
X162881Y617266D03*
X153417Y617244D03*
X161200Y723900D03*
X150200Y729400D03*
X153700D03*
X157700Y748900D03*
X154000Y779000D03*
X143000Y784500D03*
X146500D03*
X150500Y804000D03*
X138500Y835000D03*
X137600Y839500D03*
X141100Y824500D03*
X141000Y830700D03*
X145900Y824400D03*
X142500Y862500D03*
Y867500D03*
Y872500D03*
X138500Y869500D03*
Y875200D03*
X141000Y877700D03*
X145500D03*
X149700D03*
X142500Y856500D03*
X159449Y878276D03*
X178577Y107902D03*
X181738Y122711D03*
X171500Y207500D03*
Y202500D03*
X193400Y192900D03*
X167000Y211500D03*
X172450Y211050D03*
X180850Y285650D03*
X176098Y444355D03*
X173471Y454700D03*
X184664Y516869D03*
X172065Y523170D03*
Y520020D03*
X175216Y520019D03*
X197500Y577300D03*
X198600Y599750D03*
Y588750D03*
X181371Y601636D03*
X193500Y700000D03*
X182500Y705500D03*
X186000D03*
X190000Y725000D03*
X177700Y723900D03*
X182860Y742240D03*
X181200Y748900D03*
X190000Y780500D03*
X170500Y779000D03*
X193500Y755500D03*
X182500Y761000D03*
X186000D03*
X175660Y797340D03*
X174000Y804000D03*
X195000Y824090D03*
X188572Y832186D03*
X196474Y832178D03*
X196000Y868700D03*
X176771Y878276D03*
X195669D03*
X168898Y878200D03*
X185500D03*
X227669Y5500D03*
X210028Y12605D03*
Y32605D03*
Y52605D03*
Y72605D03*
X226533Y72591D03*
X228121Y63589D03*
X210028Y92605D03*
X227989Y83589D03*
X228500Y138100D03*
X223750Y141370D03*
X218725Y138175D03*
X224500Y170500D03*
Y174700D03*
Y166300D03*
X213282Y188452D03*
X202892Y188441D03*
X224500Y178900D03*
X205013Y192596D03*
X218102Y334880D03*
X218070Y340244D03*
X219763Y472187D03*
X216600Y496550D03*
X217800Y512500D03*
X221000Y541300D03*
X217500Y519800D03*
Y529250D03*
X216300Y550500D03*
X216278Y567341D03*
X216090Y593937D03*
X210000Y700000D03*
X213500Y725000D03*
X215160Y718340D03*
X227409Y775903D03*
X233000D03*
X213500Y780500D03*
X210000Y755500D03*
X215160Y773840D03*
X203124Y824090D03*
X233650Y827374D03*
X208700Y828000D03*
X201641Y827947D03*
X214380Y827374D03*
X221052D03*
X226978D03*
X201500Y868700D03*
X233464Y878276D03*
X208267D03*
X201969D03*
X220866D03*
X214567D03*
X227166D03*
X247669Y5500D03*
X258159Y73589D03*
X257851Y63589D03*
X257769Y83589D03*
X264500Y142750D03*
X259500Y138500D03*
X254500Y142750D03*
X259500Y143250D03*
Y147750D03*
Y160750D03*
Y156250D03*
X264397Y160977D03*
X264500Y157250D03*
Y153750D03*
Y150250D03*
Y146250D03*
X259500Y152000D03*
X254500Y161250D03*
Y157250D03*
Y153750D03*
Y150250D03*
Y146250D03*
X261500Y173500D03*
X253000Y166500D03*
X258700D03*
X262900D03*
X239600Y142900D03*
X261500Y179000D03*
Y184500D03*
X261000Y190500D03*
X258225Y193963D03*
X266500Y184500D03*
Y190500D03*
X241231Y238869D03*
X236300Y227280D03*
X247500Y233750D03*
X267300Y300600D03*
Y328640D03*
X257340Y338640D03*
X260929Y345571D03*
X248930Y358000D03*
X260646Y499181D03*
X256855Y499154D03*
X265019Y497483D03*
X255487Y512454D03*
X249700Y525737D03*
Y521250D03*
X252238Y574238D03*
X266100Y614400D03*
X265850Y606400D03*
X248500Y583000D03*
X260100Y647400D03*
X259300Y632400D03*
Y639300D03*
X250500Y642500D03*
X265900Y622400D03*
X238100Y643400D03*
X247717Y633233D03*
X259300Y635900D03*
X266906Y775531D03*
X249025Y827374D03*
X255697D03*
X261624D03*
X261811Y878276D03*
X249212D03*
X239764D03*
X255511D03*
X267669Y5500D03*
X271000Y184500D03*
X269849Y308414D03*
X269270Y315759D03*
X297729Y362571D03*
X284200Y465000D03*
X286181Y498546D03*
X291500Y497700D03*
X269000Y504962D03*
X275286Y504392D03*
X280749Y512744D03*
X300835Y578165D03*
Y583165D03*
X301000Y588665D03*
X288835Y593165D03*
X276300Y617350D03*
X281700Y634900D03*
X281100Y651700D03*
X285500Y704900D03*
X294000Y716000D03*
X278406Y716531D03*
X274406Y716598D03*
X270000Y732650D03*
X283161Y730092D03*
X281500Y748500D03*
X282378Y775431D03*
X298500Y752000D03*
X272116Y755592D03*
X298400Y775700D03*
X268296Y827374D03*
X280894D03*
X274222D03*
X286800Y863300D03*
X280800Y863500D03*
X268110Y878276D03*
X280708D03*
X287008D03*
X274410D03*
X329500Y192500D03*
X328000Y197400D03*
X334500Y197500D03*
Y192500D03*
X307300Y221702D03*
X307834Y237966D03*
X328842Y300042D03*
X316420Y331830D03*
X302749Y332651D03*
X326041Y329282D03*
X313875Y364201D03*
X310475Y364193D03*
X316315Y369889D03*
X316205Y376006D03*
X306612Y460177D03*
X307400Y467600D03*
X303440Y475360D03*
X303500Y491000D03*
X322700Y536500D03*
X311406Y535944D03*
X322100Y638500D03*
X322178Y729178D03*
X310016Y729793D03*
X312500Y716500D03*
X313452Y753856D03*
X330000Y754000D03*
X312017Y827374D03*
X318689D03*
X324616D03*
X331288D03*
X306500Y868700D03*
X312000Y868600D03*
X324803Y878276D03*
X331102D03*
X318503D03*
X312500Y878200D03*
X344000Y197500D03*
X339500D03*
X344000Y192500D03*
X339500D03*
X344958Y300740D03*
X344955Y305843D03*
X359500Y448800D03*
X342300Y511600D03*
X350000Y537600D03*
X347100Y605300D03*
X357600Y638300D03*
X366792Y734171D03*
X364275Y723033D03*
X359500Y727335D03*
X342900Y727200D03*
X349813Y827374D03*
X356485D03*
X362411D03*
X343886D03*
X337214D03*
X362599Y878276D03*
X356299D03*
X350000D03*
X343700D03*
X337402D03*
X387669Y5500D03*
X401300Y159800D03*
X401200Y150200D03*
X395100Y449100D03*
X380300Y508700D03*
X401000Y575500D03*
X372000Y579300D03*
X388900Y550400D03*
X386500Y607900D03*
X374275Y722919D03*
X369083Y827374D03*
X384459D03*
X391131D03*
X397057D03*
X378346Y878276D03*
X390944D03*
X397244D03*
X384646D03*
X370500Y878200D03*
X407669Y5500D03*
X427669D03*
X406500Y141700D03*
Y146900D03*
X404170Y326708D03*
X403900Y315492D03*
X416100Y470800D03*
X418900Y529300D03*
X410300Y637500D03*
X416328Y827374D03*
X428926D03*
X422254D03*
X403729D03*
X409656D03*
X416141Y878276D03*
X431889D03*
X422441D03*
X403543D03*
X409843D03*
X447669Y5500D03*
X467669D03*
X461900Y62300D03*
X452600Y114254D03*
X454871Y122291D03*
X457400Y138900D03*
X452500Y153300D03*
X455800Y208300D03*
X461389Y318510D03*
X459200Y369300D03*
X462700D03*
X466700Y388800D03*
X448200Y531400D03*
X443000Y596500D03*
X456335Y835051D03*
X444500Y864450D03*
X438189Y878276D03*
X489261Y-14185D03*
X470200Y62300D03*
X478400D03*
X479700Y90100D03*
X491466Y126683D03*
X494800Y162900D03*
X493186Y272414D03*
X501867Y295490D03*
X486700Y363800D03*
X470200D03*
X490200Y388800D03*
X491860Y382140D03*
X472600Y477700D03*
X487400Y492100D03*
X500800Y567200D03*
X487906Y768598D03*
X491906Y768531D03*
X496061Y781678D03*
X494582Y800500D03*
X483500Y784650D03*
X485300Y808250D03*
X496335Y835051D03*
X480406Y827531D03*
X495878Y827431D03*
X514309Y-315D03*
Y52087D03*
X530057Y67048D03*
Y52087D03*
X530400Y72400D03*
X524000Y43500D03*
X532500Y62900D03*
X536100Y56700D03*
X530057Y106457D03*
Y96969D03*
Y82008D03*
X531400Y102900D03*
X522700D03*
X528700Y91100D03*
X531200Y87900D03*
X535400Y87400D03*
X532900Y92400D03*
X532400Y78200D03*
X521465Y140964D03*
X513876D03*
X532110Y138400D03*
X525000D03*
X506006Y126183D03*
X515348Y163101D03*
X515354Y168998D03*
X505100Y164800D03*
X512600Y186500D03*
X534481Y243676D03*
X518277Y288680D03*
X532921Y298436D03*
X525347Y336979D03*
X512100Y319700D03*
X532499Y315591D03*
X533779Y336979D03*
X507809Y336341D03*
X522209Y333841D03*
X522409Y318441D03*
X518100Y453200D03*
X520500Y519400D03*
X527700Y587500D03*
X522500Y782031D03*
X535178Y781000D03*
X511800Y768300D03*
X528100Y767300D03*
X526274Y806000D03*
X511500Y803000D03*
X533800Y835500D03*
X527941Y864680D03*
X557616Y-315D03*
Y52087D03*
X538915Y67048D03*
X547773D03*
Y52087D03*
X538915D03*
X541200Y73400D03*
X541600Y62600D03*
X544500Y57400D03*
X546800Y46300D03*
X566700Y48700D03*
X570900Y56200D03*
X547773Y106457D03*
X538915Y96969D03*
X547773D03*
X538915Y82008D03*
X547773D03*
X537400Y91000D03*
X540100Y102900D03*
X541700Y92300D03*
X544600Y87300D03*
X538800Y76900D03*
X546800Y76200D03*
X566100Y103100D03*
X543000Y76300D03*
X539031Y136200D03*
X547400Y136170D03*
X560633Y127988D03*
X552800Y140800D03*
X543900Y154800D03*
X550300D03*
X554149Y200229D03*
X541446Y222562D03*
X565063Y256608D03*
Y247608D03*
Y252108D03*
X560318Y267199D03*
Y272199D03*
X560418Y278299D03*
Y283799D03*
Y289299D03*
X560318Y295699D03*
X539450Y322166D03*
X539507Y330787D03*
X554400Y335900D03*
X560531Y358080D03*
X564100Y358100D03*
X556500Y358000D03*
X561781Y346281D03*
X550000Y381000D03*
X542500Y806000D03*
X550186Y827374D03*
X543514D03*
X568711D03*
X556113D03*
X562785D03*
X538000Y878200D03*
X550000Y878276D03*
X562598D03*
X568898D03*
X556300D03*
X544000Y878200D03*
X600923Y-315D03*
Y52087D03*
X573364D03*
X582222D03*
X591080D03*
X573364Y67048D03*
X582222D03*
X591080D03*
X590000Y46200D03*
X579900Y55800D03*
X588000Y57200D03*
X584600Y63200D03*
X575800Y63100D03*
X588000Y72200D03*
X579000Y72300D03*
X573800Y72400D03*
X591080Y106457D03*
X573364D03*
X582222Y82008D03*
X591080D03*
X573364D03*
Y96969D03*
X582222D03*
X591080D03*
X576800Y91600D03*
X584600Y78200D03*
X575500Y78500D03*
X588000Y87100D03*
X579000Y87200D03*
X584500Y93200D03*
X580700Y90900D03*
X572500Y91200D03*
X576300Y103300D03*
X585100D03*
X580800Y76000D03*
X574100Y87800D03*
X579200Y140400D03*
X583640Y140636D03*
X598240Y137800D03*
X572990Y140501D03*
X588955Y140600D03*
X591377Y125797D03*
X597846Y125623D03*
X593000Y152800D03*
X598300Y152850D03*
X597763Y242608D03*
X602763Y240858D03*
X597763Y231608D03*
Y235108D03*
Y239108D03*
X602763Y236608D03*
Y232108D03*
X587100Y234800D03*
X597763Y246108D03*
Y250108D03*
X602763Y245108D03*
Y249608D03*
X605063Y257608D03*
X604170Y337900D03*
X599100Y348700D03*
X597500Y352050D03*
X589500Y361000D03*
X581700Y360700D03*
X573900Y360600D03*
X603500Y371200D03*
X576800Y369200D03*
X584500Y462500D03*
X600400Y538000D03*
X586900Y713200D03*
X593908Y827374D03*
X600580D03*
X587981D03*
X581309D03*
X575383D03*
X594095Y878276D03*
X600393D03*
X587795D03*
X575197D03*
X581497D03*
X616671Y52087D03*
X625529D03*
X634388D03*
X616671Y67048D03*
X625529D03*
X634388D03*
X631100Y72300D03*
X622100Y72400D03*
X628200Y62600D03*
X619200Y62800D03*
X614300Y55800D03*
X620838Y58628D03*
X634100Y46800D03*
X631300Y57100D03*
X616800Y72200D03*
X624700Y61400D03*
X634388Y106457D03*
X616671D03*
X625529Y82008D03*
X634388D03*
X616671D03*
Y96969D03*
X625529D03*
X634388D03*
X611100Y103300D03*
X619600D03*
X628300D03*
X615800Y91200D03*
X624400Y91100D03*
X628000Y93000D03*
X618300Y88000D03*
X628100Y77700D03*
X619400Y77500D03*
X631200Y87200D03*
X624000Y76000D03*
X621900Y87600D03*
X619700Y92100D03*
X629393Y140451D03*
X631940Y137800D03*
X607520Y137780D03*
X605924Y126398D03*
X633900Y149600D03*
X607763Y242608D03*
Y231608D03*
Y235108D03*
Y239108D03*
X619363Y225108D03*
X623363D03*
X611563Y278108D03*
X607763Y246108D03*
Y250108D03*
X607563Y265608D03*
X607463Y270608D03*
X607563Y261108D03*
X609063Y255608D03*
X607563Y276108D03*
Y282108D03*
Y287608D03*
Y293608D03*
X607519Y299497D03*
X611563Y290108D03*
Y284608D03*
X635350Y320850D03*
X606322Y351522D03*
X633000Y356600D03*
Y360500D03*
Y353000D03*
X636500Y356500D03*
X629500D03*
Y371000D03*
X626458Y372521D03*
X616706Y349718D03*
X618680Y346780D03*
X621300Y366900D03*
X609500Y360717D03*
X623000Y382500D03*
X617000D03*
X627600Y685000D03*
X608000Y700800D03*
X613178Y827374D03*
X606506D03*
X638375D03*
X631703D03*
X619105D03*
X625777D03*
X606693Y878276D03*
X619292D03*
X612992D03*
X625590D03*
X631890D03*
X644230Y-315D03*
Y52087D03*
X659978D03*
X668836D03*
X659978Y67048D03*
X668836D03*
X653300Y48600D03*
X665400Y72500D03*
X661100Y73000D03*
X662300Y63300D03*
X656700Y57400D03*
X665696Y57027D03*
X671100Y63400D03*
X659978Y106457D03*
X668836Y82008D03*
X659978D03*
Y96969D03*
X668836D03*
X656400Y102600D03*
X665100Y102700D03*
X660600Y93300D03*
X669400Y93200D03*
X659700Y86400D03*
X662400Y78100D03*
X667500Y76000D03*
X664000Y91100D03*
X671300Y78100D03*
X641159Y137800D03*
X643160Y149600D03*
X666593Y226677D03*
X662593Y223677D03*
X658093D03*
X671124Y210770D03*
X655500Y213500D03*
X672100Y299800D03*
X640532Y318099D03*
X643932Y318104D03*
X639500Y342500D03*
X652254Y336353D03*
X662897Y346873D03*
X663140Y353982D03*
X646884Y355616D03*
X639500Y371000D03*
X653000Y380500D03*
X644100Y488700D03*
X639500Y678500D03*
X657000Y714500D03*
X668500Y700000D03*
X648900Y782500D03*
X666348Y827374D03*
X653750D03*
X660422D03*
X653500Y819100D03*
X647838Y872000D03*
X660236Y878276D03*
X666536D03*
X654000Y878200D03*
X642200Y877900D03*
X687537Y-315D03*
Y52087D03*
X677695D03*
Y67048D03*
X674600Y72200D03*
X676800Y46300D03*
X677695Y106457D03*
Y82008D03*
Y96969D03*
X674300Y102400D03*
X678300Y93100D03*
X674800Y86800D03*
X678063Y238108D03*
X673063D03*
X672927Y219677D03*
X677927D03*
X686063Y230108D03*
X696800Y237900D03*
X682763Y238008D03*
X686063Y224608D03*
X703600Y233700D03*
X687253Y237878D03*
X691753D03*
X698300Y226500D03*
X693800D03*
X685115Y210677D03*
X677000Y299900D03*
X682063Y299108D03*
X683800Y295000D03*
X684063Y285908D03*
Y290408D03*
X689500Y344000D03*
X704500Y343000D03*
X676700Y378800D03*
X687000Y378700D03*
X678500Y684000D03*
X673020Y827374D03*
X698217D03*
X691545D03*
X678947D03*
X685619D03*
X698100Y821600D03*
X703900Y866100D03*
X697700D03*
X704331Y878276D03*
X698031D03*
X691733D03*
X685433D03*
X679134D03*
X672834D03*
X736308Y-7483D03*
X711919Y6754D03*
X729555Y33100D03*
X709120Y35980D03*
X719555Y33100D03*
X735186Y20714D03*
X727265Y52588D03*
X726646Y42651D03*
X721690Y53340D03*
X723501Y82680D03*
X723481Y76780D03*
X723610Y106430D03*
X723569Y100969D03*
X723659Y97292D03*
X723429Y91683D03*
X735157Y97005D03*
X735326Y102660D03*
X723438Y112700D03*
X723638Y118353D03*
X725300Y228700D03*
X730300D03*
X711300D03*
X716300D03*
X716900Y233800D03*
X721400D03*
X730400D03*
X725900D03*
X735400D03*
X707900D03*
X712400D03*
X706800Y290700D03*
X718800Y291000D03*
X714300D03*
X707363Y298108D03*
X718863Y295908D03*
X714363D03*
X723300Y291000D03*
X732300D03*
X727800D03*
X723363Y295908D03*
X732363D03*
X727863D03*
X737300Y291000D03*
X724400Y626500D03*
X735640Y827374D03*
X723041D03*
X729713D03*
X729527Y878276D03*
X735827D03*
X723000Y878200D03*
X752763Y38638D03*
X771600Y24200D03*
X747000Y44300D03*
X762250Y44650D03*
X753500Y96600D03*
X762400Y127600D03*
X753500Y110900D03*
X769400Y111900D03*
X771400Y185919D03*
X766244Y185897D03*
X748237Y194042D03*
X751737D03*
X743500Y362000D03*
X753000Y359000D03*
X743000Y598000D03*
X773435Y827374D03*
X754910D03*
X748238D03*
X742312D03*
X760837D03*
X767509D03*
X754724Y878276D03*
X761024D03*
X767323D03*
X742126D03*
X748426D03*
X788550Y29350D03*
X781500Y85100D03*
X797800Y104500D03*
X776538Y107162D03*
X773900Y138300D03*
X796051Y175147D03*
X796089Y181182D03*
X775397Y179165D03*
Y184215D03*
X792390Y199166D03*
X786463Y199019D03*
X803169Y198850D03*
X797890Y198918D03*
X780800Y545900D03*
X786033Y827374D03*
X780107D03*
X792705D03*
X798632D03*
X805304D03*
X779921Y878276D03*
X786221D03*
X792519D03*
X798819D03*
X805118D03*
X773623D03*
X830773Y9000D03*
X834227D03*
X831592Y34411D03*
X832401Y46472D03*
X831125Y67775D03*
X833900Y467000D03*
X812500Y499400D03*
X836427Y827374D03*
X817902D03*
X811230D03*
X836615Y878276D03*
X830315D03*
X811418D03*
X820000Y878200D03*
X867600Y2500D03*
X855489Y9811D03*
X859300Y9900D03*
X874300Y18875D03*
X858500Y40000D03*
Y32000D03*
X869447Y31024D03*
X843500Y9150D03*
X859200Y47100D03*
X847337Y46563D03*
X851300Y45748D03*
X844900Y85100D03*
X874410Y127953D03*
Y163386D03*
Y202755D03*
Y242125D03*
Y238188D03*
Y257873D03*
Y253936D03*
Y249999D03*
Y246062D03*
X851500Y705500D03*
X852500Y718000D03*
X847500Y717500D03*
X857406Y745598D03*
X861406Y745531D03*
X855500Y775500D03*
X844150Y762150D03*
X858695Y759900D03*
X871000Y776500D03*
X849906Y804531D03*
X865378Y804431D03*
X851890Y789270D03*
X870900Y812104D03*
X855697Y827374D03*
X849025D03*
X843099D03*
X861823Y853696D03*
X849213Y878276D03*
X842913D03*
X856000Y878200D03*
X904262Y14894D03*
X887800Y40100D03*
X880883Y30583D03*
X892745Y9681D03*
X907750Y51750D03*
X894110Y49250D03*
X878800Y49600D03*
X875050Y56250D03*
X895080Y52828D03*
X890000Y97800D03*
X897000Y96700D03*
X894095Y139764D03*
X905906Y124016D03*
Y120079D03*
Y116142D03*
X901969Y124016D03*
X894095D03*
X890158Y127953D03*
X901969D03*
X898032D03*
X894095D03*
X882284Y139764D03*
X886221Y135827D03*
X882284Y131890D03*
X886221Y124016D03*
X878347D03*
X886221Y127953D03*
X882284D03*
X878347D03*
X901969Y167323D03*
X905906D03*
X901969Y171260D03*
X905906D03*
X901969Y175197D03*
X905906D03*
X890158Y163386D03*
X894095Y167323D03*
Y175197D03*
X905906Y159449D03*
X901969D03*
X894095Y155512D03*
Y147638D03*
X882284Y167323D03*
X886221Y163386D03*
X882284D03*
X878347D03*
X886221Y159449D03*
X882284Y155512D03*
X886221Y151575D03*
X882284Y147638D03*
X886221Y143701D03*
X901969Y194881D03*
X905906D03*
X901969Y198818D03*
X905906D03*
X901969Y202755D03*
X905906D03*
X901969Y206692D03*
X905906D03*
X890158Y202755D03*
X898032Y206692D03*
X894095D03*
Y194881D03*
X901969Y179134D03*
X905906D03*
X901969Y190944D03*
X905906D03*
X894095Y183071D03*
X882284Y206692D03*
X886221Y202755D03*
X882284D03*
X878347D03*
X886221Y198818D03*
X882284Y194881D03*
X886221Y190944D03*
Y179134D03*
X901969Y222440D03*
X905906D03*
X901969Y226377D03*
X905906D03*
Y234251D03*
X901969Y230314D03*
X905906D03*
X901969Y234251D03*
X894095Y222440D03*
X890158Y238188D03*
X894095Y242125D03*
Y230314D03*
X901969Y242125D03*
Y210629D03*
X905906D03*
X901969Y214566D03*
X905906D03*
X901969Y218503D03*
X905906D03*
X894095Y214566D03*
X886221Y226377D03*
X882284Y222440D03*
X886221Y242125D03*
X878347D03*
X886221Y238188D03*
X882284D03*
X878347D03*
X886221Y234251D03*
X882284Y230314D03*
X886221Y218503D03*
X882284Y214566D03*
X886221Y210629D03*
X901969Y253936D03*
X894095D03*
X890158Y249999D03*
X905906D03*
X898032D03*
X878347Y253936D03*
X886221D03*
X882284Y249999D03*
X908500Y270500D03*
Y275000D03*
Y267000D03*
X907500Y325000D03*
X902500Y370000D03*
X897000Y370500D03*
X907500Y368000D03*
X900999Y748550D03*
X885400Y743600D03*
X900824Y781531D03*
X895278Y758885D03*
X874887Y759253D03*
X884671Y775500D03*
X885167Y816593D03*
X884412Y835051D03*
X912000Y41000D03*
X927250Y31450D03*
X912000Y45000D03*
X926500Y60050D03*
X930500Y57500D03*
X935000Y97400D03*
X927100Y96900D03*
X941339Y139764D03*
X933465D03*
X921654Y135827D03*
X941339Y124016D03*
Y120079D03*
Y116142D03*
X937402Y124016D03*
X933465Y127953D03*
X929528Y124016D03*
X925591Y127953D03*
X921654Y124016D03*
X917717Y127953D03*
X909843Y135827D03*
X913780Y124016D03*
X909843Y127953D03*
X941339Y175197D03*
Y167323D03*
X933465Y175197D03*
X937402Y171260D03*
X933465Y167323D03*
X937402Y163386D03*
X929528Y171260D03*
X925591Y175197D03*
X921654Y163386D03*
X925591Y167323D03*
X917717D03*
X921654Y171260D03*
X917717Y175197D03*
X929528Y163386D03*
X941339Y159449D03*
X937402Y151575D03*
X933465Y159449D03*
X925591D03*
X921654Y147638D03*
X909843Y163386D03*
X913780D03*
X909843Y167323D03*
X913780D03*
X909843Y171260D03*
X913780D03*
X909843Y175197D03*
X913780D03*
X909843Y147638D03*
X925591Y194881D03*
X921654Y198818D03*
X917717Y202755D03*
X937402Y206692D03*
X941339Y202755D03*
Y194881D03*
X937402Y198818D03*
X933465Y202755D03*
X929528Y206692D03*
X933465Y194881D03*
X929528Y198818D03*
X925591Y202755D03*
X921654Y206692D03*
X917717Y194881D03*
X937402Y179134D03*
X933465Y183071D03*
X929528Y190944D03*
Y179134D03*
X925591Y183071D03*
X921654Y179134D03*
X937402Y190944D03*
X917717Y183071D03*
X921654Y190944D03*
X909843Y194881D03*
X913780D03*
X909843Y198818D03*
X913780D03*
X909843Y202755D03*
X913780D03*
X909843Y206692D03*
X913780D03*
X909843Y179134D03*
X913780D03*
X909843Y183071D03*
Y190944D03*
X913780D03*
X917717Y222440D03*
Y226377D03*
X921654Y222440D03*
Y226377D03*
X917717Y230314D03*
Y234251D03*
X921654Y230314D03*
Y234251D03*
X925591Y230314D03*
Y222440D03*
X933465D03*
X941339D03*
X937402Y226377D03*
X929528D03*
X941339Y238188D03*
Y230314D03*
X937402Y242125D03*
Y234251D03*
X933465Y238188D03*
Y230314D03*
X929528Y242125D03*
Y234251D03*
X925591Y238188D03*
X921654Y242125D03*
X929528Y214566D03*
X933465Y210629D03*
X925591D03*
X917717D03*
X921654Y218503D03*
X925591D03*
X929528D03*
X933465D03*
X937402D03*
X941339D03*
X921654Y214566D03*
X917717Y218503D03*
X937402Y214566D03*
X913780Y226377D03*
X909843Y222440D03*
X913780D03*
X909843Y226377D03*
Y230314D03*
Y234251D03*
X913780Y230314D03*
Y234251D03*
Y242125D03*
X909843D03*
Y214566D03*
Y210629D03*
X913780D03*
X909843Y218503D03*
X913780D03*
X937402Y253936D03*
X929528D03*
X921654D03*
X941339Y249999D03*
X933465D03*
X925591D03*
X917717D03*
X913780Y253936D03*
X909843Y261810D03*
Y257873D03*
Y253936D03*
Y249999D03*
Y246062D03*
X909000Y279000D03*
X909500Y283000D03*
Y338000D03*
X909000Y353600D03*
X908700Y347300D03*
X938898Y640169D03*
X916319Y678588D03*
Y658588D03*
Y698588D03*
Y738588D03*
Y718588D03*
Y778588D03*
Y758588D03*
Y798588D03*
Y818588D03*
X969100Y14600D03*
X976066Y26581D03*
X971466Y26681D03*
X942500Y30100D03*
X975086Y61900D03*
X970000Y61050D03*
X952500Y75100D03*
X956500Y108000D03*
X949500Y103000D03*
Y97500D03*
X953149Y135827D03*
X968897Y139764D03*
X953149Y124016D03*
Y120079D03*
Y116142D03*
X972834Y124016D03*
X968897Y127953D03*
X964960Y124016D03*
X961023Y127953D03*
X957086Y124016D03*
X953149Y167323D03*
X957086Y163386D03*
X949212Y171260D03*
Y163386D03*
X972834Y171260D03*
X968897Y175197D03*
X972834Y163386D03*
X968897Y167323D03*
X964960Y171260D03*
X961023Y175197D03*
Y167323D03*
X964960Y163386D03*
X953149Y175197D03*
X957086Y171260D03*
X953149Y159449D03*
X949212Y151575D03*
X972834Y147638D03*
X968897Y159449D03*
X961023D03*
Y147638D03*
X964960Y198818D03*
X961023Y202755D03*
X957086Y206692D03*
X968897Y194881D03*
X953149D03*
X949212Y198818D03*
Y206692D03*
X953149Y202755D03*
X961023Y194881D03*
X957086Y198818D03*
X972834Y206692D03*
Y198818D03*
X968897Y202755D03*
X964960Y206692D03*
X972834Y190944D03*
X964960Y179134D03*
X961023Y183071D03*
X957086Y190944D03*
X953149Y183071D03*
X957086Y179134D03*
X949212D03*
X964960Y190944D03*
X968897Y183071D03*
X972834Y179134D03*
Y222440D03*
Y226377D03*
Y230314D03*
Y234251D03*
X968897Y230314D03*
Y222440D03*
X953149D03*
X961023D03*
X972834Y242125D03*
X949212Y226377D03*
X964960D03*
X957086D03*
X953149Y238188D03*
Y230314D03*
X949212Y242125D03*
Y234251D03*
X968897Y238188D03*
X964960Y242125D03*
Y234251D03*
X961023Y238188D03*
Y230314D03*
X957086Y242125D03*
Y234251D03*
X949212Y214566D03*
X953149Y210629D03*
X968897D03*
X964960Y214566D03*
X972834Y218503D03*
X949212D03*
X953149D03*
X957086Y214566D03*
X961023Y210629D03*
X972834Y214566D03*
X957086Y218503D03*
X961023D03*
X964960D03*
X968897D03*
X972834Y253936D03*
X949212Y261810D03*
Y257873D03*
Y253936D03*
X964960D03*
X957086D03*
X953149Y249999D03*
X949212D03*
Y246062D03*
X968897Y249999D03*
X961023D03*
X957800Y570300D03*
X958898Y640169D03*
X976500Y4500D03*
X980100Y14500D03*
X1000985Y29307D03*
X1007921Y39585D03*
X980566Y26581D03*
X985315Y14425D03*
X997385Y29307D03*
X992396Y45073D03*
X1008267Y135827D03*
Y127953D03*
Y124016D03*
X984645Y135827D03*
X1000393Y139764D03*
X992519Y127953D03*
Y124016D03*
X988582Y127953D03*
Y124016D03*
Y120079D03*
Y116142D03*
X984645Y127953D03*
X980708Y124016D03*
X996456Y127953D03*
X1000393Y124016D03*
Y127953D03*
X1004330D03*
X976771D03*
X1008267Y163386D03*
Y171260D03*
Y159449D03*
Y143701D03*
Y151575D03*
X980708Y163386D03*
X984645D03*
X988582Y167323D03*
X992519D03*
X980708D03*
X984645D03*
X988582Y171260D03*
X992519D03*
X980708D03*
X984645D03*
X988582Y175197D03*
X992519D03*
X984645D03*
X1000393Y167323D03*
X1004330Y163386D03*
X1000393Y175197D03*
X988582Y159449D03*
X992519D03*
X984645Y147638D03*
X1000393D03*
Y155512D03*
X976771Y167323D03*
Y175197D03*
X1008267Y202755D03*
Y198818D03*
Y190944D03*
Y179134D03*
X980708Y198818D03*
X988582Y194881D03*
X992519D03*
X980708D03*
X984645D03*
X988582Y198818D03*
X992519D03*
X984645D03*
X988582Y202755D03*
X992519D03*
X980708D03*
X984645D03*
X988582Y206692D03*
X992519D03*
X980708D03*
X984645D03*
X1000393D03*
X996456D03*
X1004330Y202755D03*
X1000393Y194881D03*
X988582Y179134D03*
X992519D03*
X988582Y190944D03*
X992519D03*
X980708D03*
X984645D03*
X980708Y179134D03*
X984645D03*
Y183071D03*
X1000393D03*
X976771Y202755D03*
Y194881D03*
Y183071D03*
X1008267Y226377D03*
Y242125D03*
Y238188D03*
Y234251D03*
Y218503D03*
Y210629D03*
X1000393Y222440D03*
X988582D03*
X992519D03*
X980708D03*
X984645D03*
X988582Y226377D03*
X992519D03*
X984645D03*
X980708D03*
X988582Y230314D03*
X992519D03*
Y234251D03*
X980708Y230314D03*
Y234251D03*
X984645Y230314D03*
Y234251D03*
X988582D03*
X1000393Y230314D03*
X1004330Y238188D03*
X1000393Y242125D03*
X980708D03*
X984645D03*
X992519D03*
X984645Y214566D03*
X988582Y210629D03*
X992519D03*
X980708D03*
X984645D03*
X988582Y214566D03*
X992519D03*
X988582Y218503D03*
X992519D03*
X980708D03*
X984645D03*
X1000393Y214566D03*
X976771Y222440D03*
Y226377D03*
Y230314D03*
Y234251D03*
Y210629D03*
Y218503D03*
X1008267Y253936D03*
X980708D03*
X984645D03*
Y257873D03*
Y261810D03*
X992519Y253936D03*
X1000393D03*
X984645Y246062D03*
Y249999D03*
X988582D03*
X996456D03*
X1004330D03*
X976771D03*
X982500Y271500D03*
Y275500D03*
X982000Y267500D03*
X983500Y279500D03*
Y283500D03*
X1006100Y528700D03*
X977500Y550000D03*
X978898Y640169D03*
X994248Y665818D03*
Y685818D03*
Y705818D03*
Y745818D03*
Y725818D03*
Y765818D03*
Y805818D03*
Y785818D03*
X1025700Y7600D03*
X1024330Y34379D03*
X1040218Y32140D03*
X1010229Y19022D03*
X1022300Y13900D03*
X1035783Y51473D03*
X1017863Y45056D03*
X1021751Y117469D03*
X1012204Y131890D03*
Y139764D03*
Y127953D03*
X1016141Y124016D03*
X1020078Y127953D03*
X1016141D03*
X1012204Y167323D03*
Y163386D03*
X1016141D03*
X1020078D03*
X1012204Y175197D03*
Y147638D03*
Y155512D03*
Y206692D03*
Y202755D03*
Y194881D03*
X1016141Y202755D03*
X1020078D03*
X1012204Y183071D03*
Y222440D03*
Y238188D03*
Y230314D03*
X1016141Y242125D03*
X1020078D03*
X1016141Y238188D03*
X1020078D03*
X1012204Y214566D03*
X1020078Y257873D03*
X1016141Y253936D03*
X1020078D03*
X1012204Y249999D03*
X1020078D03*
Y246062D03*
X1012600Y476700D03*
X1022600Y542100D03*
X1017800Y572700D03*
X1043300Y631300D03*
X1041500Y682000D03*
X1041900Y658100D03*
X1039577Y827374D03*
X1024004Y855893D03*
X1033464Y878276D03*
X1039764D03*
X1069261Y-14185D03*
X1049261D03*
X1061253Y17487D03*
X1062470Y31823D03*
X1062433Y37099D03*
X1056049Y18396D03*
X1061153Y27488D03*
X1046200Y24500D03*
X1054835Y40386D03*
X1072140Y16447D03*
X1047429Y15229D03*
X1054210Y53370D03*
X1054090Y58470D03*
X1068315Y56120D03*
X1068390Y61611D03*
X1074103Y44988D03*
X1047000Y644000D03*
X1045000Y617500D03*
X1067000Y711000D03*
X1062500Y738000D03*
X1058500Y758000D03*
X1058847Y827374D03*
X1052175D03*
X1046249D03*
X1064774D03*
X1071446D03*
X1046063Y878276D03*
X1071260D03*
X1064961D03*
X1058661D03*
X1052363D03*
X1089261Y-14185D03*
X1103424Y67690D03*
X1110664Y78483D03*
X1103253Y76910D03*
X1079500Y631000D03*
X1080000Y650500D03*
X1081000Y670000D03*
X1084044Y827374D03*
X1077372D03*
X1102569D03*
X1109241D03*
X1089970D03*
X1096642D03*
X1090158Y878276D03*
X1083858D03*
X1077560D03*
X1096456D03*
X1102756D03*
X1109055D03*
X1116671Y-315D03*
Y52087D03*
X1132419Y67048D03*
X1141277D03*
Y52087D03*
X1132419D03*
X1127300Y46300D03*
X1122800Y55100D03*
X1132100Y56300D03*
X1131900Y70700D03*
X1140900Y71100D03*
X1141900Y63300D03*
X1132419Y106457D03*
Y96969D03*
X1141277D03*
X1132419Y82008D03*
X1141277D03*
X1142418Y78638D03*
X1131800Y85600D03*
X1141200Y86800D03*
X1126400Y92200D03*
X1143500Y93300D03*
X1123000Y99200D03*
X1131880Y100377D03*
X1134800Y93300D03*
X1116933Y85243D03*
X1122001Y126574D03*
Y136874D03*
X1135150Y137851D03*
X1126500Y222500D03*
X1135750Y228750D03*
X1140364Y827374D03*
X1121839D03*
X1115167D03*
X1127766D03*
X1134438D03*
X1140552Y878276D03*
X1115355D03*
X1127953D03*
X1134252D03*
X1121653D03*
X1159978Y-315D03*
Y52087D03*
X1175726D03*
Y67048D03*
X1150135D03*
Y52087D03*
X1175300Y71100D03*
X1175100Y55700D03*
X1166500Y56200D03*
X1171700Y45900D03*
X1149100Y46300D03*
X1150700Y63300D03*
X1175726Y106457D03*
X1150135D03*
X1175726Y82008D03*
Y96969D03*
X1150135D03*
Y82008D03*
X1148900Y75900D03*
X1168400Y103000D03*
X1177000Y102800D03*
X1176200Y92900D03*
X1178100Y78000D03*
X1175200Y85900D03*
X1151492Y78668D03*
X1164857Y138505D03*
X1154557D03*
X1145450Y137851D03*
X1175851Y142410D03*
X1150250Y228750D03*
X1171300Y215700D03*
X1166300D03*
X1175999D03*
X1168000Y280000D03*
X1173000D03*
X1177500D03*
X1161700Y818500D03*
X1159634Y827374D03*
X1152962D03*
X1147036D03*
X1175010D03*
X1174900Y818300D03*
X1159448Y878276D03*
X1153150D03*
X1173623Y878200D03*
X1146850Y878276D03*
X1165748D03*
X1203285Y-315D03*
Y52087D03*
X1184584D03*
X1193442D03*
X1184584Y67048D03*
X1193442D03*
X1185200Y72600D03*
X1210511Y52300D03*
X1193555Y61875D03*
X1183884Y61598D03*
X1188200Y61600D03*
X1192300Y46100D03*
X1184100Y56100D03*
X1193442Y106457D03*
X1184584Y82008D03*
X1193442D03*
X1184584Y96969D03*
X1193442D03*
X1193900Y78000D03*
X1211500Y102900D03*
X1194000Y93200D03*
X1185800Y102900D03*
X1185100Y93000D03*
X1187100Y77900D03*
X1184800Y87200D03*
X1202410Y142850D03*
X1193845Y137855D03*
X1184629Y137740D03*
X1185070Y142384D03*
X1210391Y156730D03*
X1200391Y156779D03*
X1193192Y142970D03*
X1190300Y215700D03*
X1185300D03*
X1208800D03*
X1203800D03*
X1180601D03*
X1199300D03*
X1194500D03*
X1187000Y280000D03*
X1192000D03*
X1205500D03*
X1210500D03*
X1182500D03*
X1201000D03*
X1196200D03*
X1205500Y334400D03*
X1194280Y827374D03*
X1187608D03*
X1181682D03*
X1200735Y864273D03*
X1194063D03*
X1200394Y878276D03*
X1194094D03*
X1187796D03*
X1181496D03*
X1246592Y-315D03*
Y52087D03*
X1219033D03*
X1227891D03*
X1236750D03*
X1219033Y67048D03*
X1227891D03*
X1236750D03*
X1231400Y58300D03*
X1215400Y57600D03*
X1216300Y72900D03*
X1235800Y46400D03*
X1228000Y57000D03*
X1218600Y56000D03*
X1214700Y46000D03*
X1221200Y63400D03*
X1230300Y63200D03*
X1228900Y72900D03*
X1236750Y106457D03*
X1219033D03*
X1227891Y82008D03*
X1236750D03*
X1219033D03*
Y96969D03*
X1227891D03*
X1236750D03*
X1230000Y78800D03*
X1221300Y78400D03*
X1219200Y87000D03*
X1229100Y87900D03*
X1232500Y90900D03*
X1229900Y103100D03*
X1228300Y93100D03*
X1219500Y93300D03*
X1220100Y102700D03*
X1219138Y137928D03*
X1227999Y142465D03*
X1236692Y137720D03*
X1237219Y142420D03*
X1228359Y137960D03*
X1229000Y210500D03*
X1242500Y209000D03*
X1232000Y194500D03*
X1237000D03*
X1226500Y201500D03*
Y194500D03*
X1244500D03*
X1214800Y215700D03*
X1227000Y279000D03*
X1242000D03*
X1232000Y292000D03*
X1237000D03*
X1227000Y285500D03*
X1244500Y292000D03*
X1242000Y343000D03*
X1235400Y364400D03*
X1213400Y355400D03*
X1214100Y469800D03*
X1237800Y524500D03*
X1232300Y568900D03*
X1238375Y827374D03*
X1231703D03*
X1219105D03*
X1225777D03*
X1244302D03*
X1217717Y878076D03*
X1225590Y878276D03*
X1231890D03*
X1244489D03*
X1238189D03*
X1262340Y52087D03*
X1271198D03*
X1280057D03*
X1262340Y67048D03*
X1271198D03*
X1280057D03*
X1261900Y71039D03*
X1265500Y61900D03*
X1272200Y72900D03*
X1275200Y61200D03*
X1269900Y61100D03*
X1279100Y46300D03*
X1272200Y57900D03*
X1258400Y45900D03*
X1254500Y51100D03*
X1280057Y106457D03*
X1262340D03*
X1271198Y82008D03*
X1280057D03*
X1262340D03*
Y96969D03*
X1271198D03*
X1280057D03*
X1271300Y77100D03*
X1273200Y103200D03*
X1256000Y103300D03*
X1263200Y102700D03*
X1270300Y91100D03*
X1262800Y93100D03*
X1254200Y96300D03*
X1275500Y91000D03*
X1272700Y88000D03*
X1265200Y77400D03*
X1261900Y86000D03*
X1275800Y75900D03*
X1252768Y141181D03*
X1278160Y140547D03*
X1257899Y142881D03*
X1245910Y137810D03*
X1273068Y140514D03*
X1262880Y142909D03*
X1247500Y209000D03*
X1252500Y194500D03*
X1263000Y210307D03*
X1257500Y194500D03*
X1263000Y202000D03*
X1262500Y194500D03*
X1247000Y279000D03*
X1262500Y279500D03*
X1252000Y292000D03*
X1257000D03*
X1262500Y286000D03*
X1258500Y335500D03*
X1266500D03*
X1273500Y397000D03*
X1257500D03*
X1254000D03*
X1259200Y471800D03*
X1259000Y680000D03*
X1265000Y672000D03*
X1253500D03*
X1278000Y689000D03*
X1263572Y827374D03*
X1269498D03*
X1276170D03*
X1256900D03*
X1250974D03*
X1263386Y878276D03*
X1275984D03*
X1257087D03*
X1269686D03*
X1250787D03*
X1289899Y-315D03*
Y52087D03*
X1291660Y140257D03*
X1297360Y140172D03*
X1301749Y125479D03*
X1282189Y144361D03*
X1287637Y144386D03*
X1297668Y155524D03*
X1290870Y186285D03*
X1311181Y186548D03*
X1297500Y351800D03*
X1291600Y495200D03*
X1296400Y542400D03*
X1294700Y593400D03*
X1302128Y674067D03*
X1306128Y674000D03*
X1285000Y694000D03*
X1280500Y706000D03*
X1310376Y687205D03*
X1301728Y711200D03*
X1310100Y732900D03*
X1294628Y733000D03*
X1304800Y811900D03*
X1288768Y827374D03*
X1282096D03*
X1307294D03*
X1301800Y878100D03*
X1294268Y872169D03*
X1288582Y878276D03*
X1282284D03*
X1307481D03*
X1324845Y130527D03*
X1325429Y148270D03*
X1327782Y192579D03*
Y200579D03*
Y207579D03*
X1328411Y237679D03*
X1327782Y215579D03*
Y221579D03*
X1327841Y228639D03*
X1332683Y240409D03*
X1328356Y242091D03*
X1328317Y246291D03*
X1332683Y244609D03*
Y248809D03*
X1337000Y263250D03*
X1332000Y261500D03*
Y265000D03*
Y268500D03*
Y272500D03*
Y257500D03*
Y254000D03*
X1342000D03*
Y257500D03*
Y261500D03*
Y265000D03*
Y268500D03*
Y272500D03*
X1337000Y267500D03*
Y272000D03*
Y259000D03*
Y254500D03*
X1322250Y282250D03*
X1345850Y676750D03*
X1326250Y669550D03*
X1333500Y709500D03*
X1323076Y686999D03*
X1338200Y689800D03*
X1315546Y709500D03*
X1341400Y686900D03*
X1326661Y740700D03*
X1345088Y827374D03*
X1332490D03*
X1339162D03*
X1326564D03*
X1319892D03*
X1313966D03*
X1320079Y878276D03*
X1345276D03*
X1332678D03*
X1338976D03*
X1326378D03*
X1313779D03*
X1368028Y175745D03*
X1366672Y210312D03*
X1375196Y217203D03*
X1367042Y223895D03*
X1375359Y230110D03*
X1372000Y240500D03*
X1368300Y267800D03*
X1358662Y275485D03*
X1372000Y245300D03*
Y249500D03*
X1369700Y424600D03*
X1366000Y472900D03*
X1363900Y537600D03*
X1361800Y596800D03*
X1358700Y655700D03*
X1348500Y713000D03*
X1377000Y725000D03*
X1378000Y806900D03*
X1369925Y835051D03*
X1351760Y827374D03*
X1357886Y864246D03*
X1352200Y878400D03*
X1394500Y139626D03*
Y119626D03*
Y159626D03*
Y199626D03*
Y179626D03*
X1381568Y180579D03*
X1394500Y239626D03*
Y219626D03*
Y259626D03*
Y299626D03*
Y279626D03*
Y339626D03*
Y319626D03*
Y359626D03*
Y399626D03*
Y379626D03*
Y439626D03*
Y419626D03*
Y479626D03*
Y459626D03*
Y499626D03*
Y539626D03*
Y519626D03*
Y579626D03*
Y559626D03*
Y599626D03*
Y639626D03*
Y619626D03*
Y679626D03*
Y659626D03*
Y699626D03*
Y739626D03*
Y719626D03*
Y759626D03*
Y779626D03*
Y799626D03*
Y819626D03*
X1389925Y835051D03*
G54D39*
X911616Y13778D03*
G54D33*
X501742Y215594D03*
G54D37*
X819291Y265354D03*
Y285354D03*
G54D10*
X700Y19100D03*
X16200Y120100D03*
X27200Y821800D03*
X33800Y872600D03*
X1384200Y122800D03*
X1373200Y823500D03*
X1415100Y-36700D03*
X1389800Y879000D03*
G54D16*
X39370Y801181D03*
X1360630Y135826D03*
Y801181D03*
G54D22*
X122165Y142874D03*
X173897D03*
G54D17*
X42587Y151614D03*
X80579D03*
G54D30*
X336417Y21260D03*
X293110Y55906D03*
X336417Y90551D03*
X789850Y236220D03*
Y283464D03*
X1376968Y21260D03*
X1333661Y55906D03*
X1376968Y90551D03*
G54D15*
X25050Y716900D03*
X71500Y297900D03*
X77100Y303800D03*
X65400D03*
X65500Y291900D03*
X77500D03*
X191000Y246500D03*
X534481Y286876D03*
G54D35*
X535962Y37520D03*
X579269D03*
X622577D03*
X665884D03*
X1138324D03*
X1181631D03*
X1224939D03*
X1268246D03*
G54D13*
X26977Y151614D03*
X96189D03*
G54D27*
X161811Y153543D03*
%LPC*%
G75*
G54D41*
G01X127746Y-260199D02*
X95746D01*
G01X127746Y-276199D02*
Y-356199D01*
G01D02*
X1310146D01*
G01X127746Y-311699D02*
X1310146D01*
G01X123746Y-260199D02*
G02I-12000J0D01*
G01X118596D02*
G02I-6850J0D01*
G01X111746Y-276199D02*
Y-244199D01*
G01X127746Y-276199D02*
X1310146D01*
G01X522646D02*
Y-356199D01*
G01X660146Y-276199D02*
Y-356199D01*
G01X775146Y-276199D02*
Y-356199D01*
G01X942646Y-276199D02*
Y-356199D01*
G01X1112646Y-276199D02*
Y-356199D01*
G01X1310146Y-276199D02*
Y-356199D01*
G01X1342146Y-260199D02*
X1310146D01*
G01X1338146D02*
G02I-12000J0D01*
G01X1332996D02*
G02I-6850J0D01*
G01X1326146Y-276199D02*
Y-244199D01*
G54D42*
G01X145579Y-328699D02*
Y-346199D01*
X154313D01*
G01X167446Y-334533D02*
Y-346199D01*
G01Y-329866D02*
X167009Y-329574D01*
Y-328991D01*
X167446Y-328699D01*
X167883Y-328991D01*
Y-329574D01*
X167446Y-329866D01*
G01X181889Y-350574D02*
X183418Y-351741D01*
X185164Y-352032D01*
X186692Y-351741D01*
X188003Y-350283D01*
X188876Y-348241D01*
Y-334533D01*
G01Y-336866D02*
X188003Y-335699D01*
X186692Y-334824D01*
X185164Y-334533D01*
X183418Y-335116D01*
X182326Y-336282D01*
X181452Y-338324D01*
X181016Y-340366D01*
X181234Y-342116D01*
X182108Y-344158D01*
X183418Y-345616D01*
X185164Y-346199D01*
X186474Y-345907D01*
X188003Y-344741D01*
X188876Y-343575D01*
G01X198734Y-346199D02*
Y-328699D01*
G01Y-337157D02*
X199826Y-335699D01*
X200918Y-334824D01*
X202664Y-334533D01*
X203974Y-334824D01*
X205503Y-335991D01*
X206158Y-337741D01*
Y-346199D01*
G01X219946Y-328699D02*
Y-346199D01*
G01X216889Y-334533D02*
X223003D01*
G01X233734Y-346199D02*
Y-334533D01*
G01Y-337449D02*
X234608Y-335991D01*
X235918Y-334824D01*
X237664Y-334533D01*
X239192Y-334824D01*
X240503Y-335991D01*
X241158Y-338032D01*
Y-346199D01*
G01X254946Y-334533D02*
Y-346199D01*
G01Y-329866D02*
X254509Y-329574D01*
Y-328991D01*
X254946Y-328699D01*
X255383Y-328991D01*
Y-329574D01*
X254946Y-329866D01*
G01X268734Y-346199D02*
Y-334533D01*
G01Y-337449D02*
X269608Y-335991D01*
X270918Y-334824D01*
X272664Y-334533D01*
X274192Y-334824D01*
X275503Y-335991D01*
X276158Y-338032D01*
Y-346199D01*
G01X286889Y-350574D02*
X288418Y-351741D01*
X290164Y-352032D01*
X291692Y-351741D01*
X293003Y-350283D01*
X293876Y-348241D01*
Y-334533D01*
G01Y-336866D02*
X293003Y-335699D01*
X291692Y-334824D01*
X290164Y-334533D01*
X288418Y-335116D01*
X287326Y-336282D01*
X286452Y-338324D01*
X286016Y-340366D01*
X286234Y-342116D01*
X287108Y-344158D01*
X288418Y-345616D01*
X290164Y-346199D01*
X291474Y-345907D01*
X293003Y-344741D01*
X293876Y-343575D01*
G01X320579Y-346199D02*
Y-328699D01*
X325819D01*
X327566Y-329574D01*
X328876Y-331616D01*
X329313Y-333949D01*
X328876Y-336282D01*
X327784Y-338032D01*
X325819Y-338908D01*
X320579D01*
G01X346813Y-346199D02*
X338079D01*
Y-328699D01*
X346813D01*
G01X343319Y-337157D02*
X338079D01*
G01X361692Y-336866D02*
X362566Y-335991D01*
X363221Y-334533D01*
X363658Y-332490D01*
X363221Y-330741D01*
X362348Y-329574D01*
X360819Y-328699D01*
X354924D01*
Y-346199D01*
X362129D01*
X363658Y-345033D01*
X364531Y-343282D01*
X364968Y-341241D01*
X364531Y-339199D01*
X363221Y-337449D01*
X361692Y-336866D01*
X354924D01*
G01X390579Y-346199D02*
Y-328699D01*
X395819D01*
X397566Y-329574D01*
X398876Y-331616D01*
X399313Y-333949D01*
X398876Y-336282D01*
X397784Y-338032D01*
X395819Y-338908D01*
X390579D01*
G01X406769Y-346199D02*
Y-328699D01*
X412446Y-343282D01*
X418123Y-328699D01*
Y-346199D01*
G01X434749Y-330158D02*
X433439Y-329282D01*
X431911Y-328699D01*
X430164D01*
X428199Y-329574D01*
X426671Y-331032D01*
X425579Y-332783D01*
X424706Y-335699D01*
X424487Y-338324D01*
X424924Y-340949D01*
X425579Y-342699D01*
X426889Y-344449D01*
X428418Y-345616D01*
X429946Y-346199D01*
X431474D01*
X433003Y-345616D01*
X434313Y-344741D01*
X435405Y-343575D01*
G01X460579Y-346199D02*
Y-328699D01*
X465819D01*
X467566Y-329574D01*
X468876Y-331616D01*
X469313Y-333949D01*
X468876Y-336282D01*
X467784Y-338032D01*
X465819Y-338908D01*
X460579D01*
G01X476987Y-328699D02*
X482446Y-346199D01*
X487905Y-328699D01*
G01X499946D02*
Y-346199D01*
G01X494924Y-328699D02*
X504968D01*
G01X284269Y-301199D02*
Y-283699D01*
X289946Y-298282D01*
X295623Y-283699D01*
Y-301199D01*
G01X307446D02*
X306136Y-300907D01*
X304826Y-299741D01*
X303952Y-297699D01*
X303516Y-295366D01*
X303952Y-293032D01*
X304826Y-290991D01*
X306136Y-289824D01*
X307446Y-289533D01*
X308756Y-289824D01*
X310066Y-290991D01*
X310939Y-293032D01*
X311158Y-295366D01*
X310939Y-297699D01*
X310066Y-299741D01*
X308756Y-300907D01*
X307446Y-301199D01*
G01X328876Y-283699D02*
Y-301199D01*
G01Y-298575D02*
X328003Y-300033D01*
X326692Y-300907D01*
X325164Y-301199D01*
X323418Y-300616D01*
X322108Y-299158D01*
X321234Y-297408D01*
X321016Y-295366D01*
X321234Y-293324D01*
X322108Y-291574D01*
X323418Y-290116D01*
X325164Y-289533D01*
X326692Y-289824D01*
X327784Y-290408D01*
X328876Y-291574D01*
G01X339171Y-293324D02*
X346158D01*
X345503Y-291282D01*
X344411Y-290116D01*
X342883Y-289533D01*
X341354Y-289824D01*
X340044Y-290699D01*
X339171Y-292741D01*
X338734Y-294491D01*
Y-296241D01*
X339171Y-297991D01*
X340263Y-299741D01*
X341573Y-300907D01*
X343101Y-301199D01*
X344629Y-300616D01*
X346158Y-298866D01*
G01X359946Y-301199D02*
Y-283699D01*
G01X556346Y-346199D02*
Y-328699D01*
X553726Y-332199D01*
G01Y-346199D02*
X558966D01*
G01X569043Y-343575D02*
X570352Y-345033D01*
X571881Y-345907D01*
X573846Y-346199D01*
X575811Y-345616D01*
X577339Y-344449D01*
X578431Y-342408D01*
X578649Y-340074D01*
X578213Y-337741D01*
X577121Y-336282D01*
X575592Y-335116D01*
X574064Y-334824D01*
X572536Y-335116D01*
X570571Y-336282D01*
X571226Y-328699D01*
X577121D01*
G01X591346Y-346199D02*
Y-328699D01*
X588726Y-332199D01*
G01Y-346199D02*
X593966D01*
G01X608846Y-328699D02*
X607099Y-329282D01*
X605789Y-330741D01*
X604916Y-332490D01*
X604261Y-334824D01*
X604043Y-337449D01*
X604261Y-340074D01*
X604916Y-342408D01*
X605789Y-344158D01*
X607099Y-345616D01*
X608846Y-346199D01*
X610592Y-345616D01*
X611903Y-344158D01*
X612776Y-342408D01*
X613431Y-340074D01*
X613649Y-337449D01*
X613431Y-334824D01*
X612776Y-332490D01*
X611903Y-330741D01*
X610592Y-329282D01*
X608846Y-328699D01*
G01X621543Y-343575D02*
X622852Y-345033D01*
X624381Y-345907D01*
X626346Y-346199D01*
X628311Y-345616D01*
X629839Y-344449D01*
X630931Y-342408D01*
X631149Y-340074D01*
X630713Y-337741D01*
X629621Y-336282D01*
X628092Y-335116D01*
X626564Y-334824D01*
X625036Y-335116D01*
X623071Y-336282D01*
X623726Y-328699D01*
X629621D01*
G01X543229Y-301199D02*
Y-283699D01*
X548469D01*
X550216Y-284574D01*
X551526Y-286616D01*
X551963Y-288949D01*
X551526Y-291282D01*
X550434Y-293032D01*
X548469Y-293908D01*
X543229D01*
G01X569899Y-285158D02*
X568589Y-284282D01*
X567061Y-283699D01*
X565314D01*
X563349Y-284574D01*
X561821Y-286032D01*
X560729Y-287783D01*
X559856Y-290699D01*
X559637Y-293324D01*
X560074Y-295949D01*
X560729Y-297699D01*
X562039Y-299449D01*
X563568Y-300616D01*
X565096Y-301199D01*
X566624D01*
X568153Y-300616D01*
X569463Y-299741D01*
X570555Y-298575D01*
G01X584342Y-291866D02*
X585216Y-290991D01*
X585871Y-289533D01*
X586308Y-287490D01*
X585871Y-285741D01*
X584998Y-284574D01*
X583469Y-283699D01*
X577574D01*
Y-301199D01*
X584779D01*
X586308Y-300033D01*
X587181Y-298282D01*
X587618Y-296241D01*
X587181Y-294199D01*
X585871Y-292449D01*
X584342Y-291866D01*
X577574D01*
G01X593546Y-307032D02*
X606646D01*
G01X612574Y-301199D02*
Y-283699D01*
X622618Y-301199D01*
Y-283699D01*
G01X635096Y-301199D02*
X633349Y-300907D01*
X631821Y-299741D01*
X630511Y-297991D01*
X629637Y-295949D01*
X629201Y-293616D01*
Y-291282D01*
X629637Y-288949D01*
X630511Y-286907D01*
X631821Y-285158D01*
X633349Y-283991D01*
X635096Y-283699D01*
X636842Y-283991D01*
X638371Y-285158D01*
X639681Y-286907D01*
X640555Y-288949D01*
X640991Y-291282D01*
Y-293616D01*
X640555Y-295949D01*
X639681Y-297991D01*
X638371Y-299741D01*
X636842Y-300907D01*
X635096Y-301199D01*
G01X685937Y-283699D02*
X691396Y-301199D01*
X696855Y-283699D01*
G01X713263Y-301199D02*
X704529D01*
Y-283699D01*
X713263D01*
G01X709769Y-292157D02*
X704529D01*
G01X722029Y-301199D02*
Y-283699D01*
X727488D01*
X729234Y-284574D01*
X730326Y-285741D01*
X730763Y-288074D01*
X730326Y-290408D01*
X729016Y-291866D01*
X727488Y-292741D01*
X722029D01*
G01X727488D02*
X730763Y-301199D01*
G01X743896Y-301782D02*
X743459Y-301491D01*
Y-300907D01*
X743896Y-300616D01*
X744333Y-300907D01*
Y-301491D01*
X743896Y-301782D01*
G01X717646Y-346199D02*
Y-328699D01*
X715026Y-332199D01*
G01Y-346199D02*
X720266D01*
G01X898213Y-328699D02*
Y-346199D01*
X889479D01*
G01X876783D02*
X876346Y-342408D01*
X875691Y-339199D01*
X874818Y-336282D01*
X873726Y-333074D01*
X871979Y-328699D01*
X880713D01*
G01X857536Y-337449D02*
X853169D01*
Y-342699D01*
X854479Y-344449D01*
X856008Y-345616D01*
X858191Y-346199D01*
X860374Y-345616D01*
X861903Y-344449D01*
X863213Y-342699D01*
X864086Y-340657D01*
X864523Y-338324D01*
Y-336282D01*
X864086Y-334533D01*
X863213Y-332490D01*
X861903Y-330741D01*
X860593Y-329574D01*
X858846Y-328699D01*
X857318D01*
X855571Y-329282D01*
X854261Y-330449D01*
G01X846368Y-346199D02*
Y-328699D01*
X836324Y-346199D01*
Y-328699D01*
G01X828649Y-346199D02*
Y-328699D01*
X824283D01*
X822536Y-329574D01*
X821226Y-330741D01*
X820134Y-332490D01*
X819261Y-334533D01*
X819043Y-337449D01*
X819261Y-340366D01*
X820134Y-342408D01*
X821226Y-344158D01*
X822536Y-345324D01*
X824283Y-346199D01*
X828649D01*
G01X819479Y-283699D02*
Y-301199D01*
X828213D01*
G01X845276D02*
Y-289533D01*
G01Y-291574D02*
X844403Y-290408D01*
X843092Y-289824D01*
X841564Y-289533D01*
X840036Y-290116D01*
X838726Y-291282D01*
X837852Y-293032D01*
X837416Y-295366D01*
X837852Y-297699D01*
X838726Y-299449D01*
X840036Y-300616D01*
X841564Y-301199D01*
X843092Y-300907D01*
X844403Y-300033D01*
X845276Y-298866D01*
G01X854261Y-306449D02*
X855571Y-307032D01*
X857318Y-306449D01*
X858409Y-305283D01*
X859283Y-303824D01*
X860592Y-299158D01*
X863431Y-289533D01*
G01X856444D02*
X860592Y-299158D01*
G01X873071Y-293324D02*
X880058D01*
X879403Y-291282D01*
X878311Y-290116D01*
X876783Y-289533D01*
X875254Y-289824D01*
X873944Y-290699D01*
X873071Y-292741D01*
X872634Y-294491D01*
Y-296241D01*
X873071Y-297991D01*
X874163Y-299741D01*
X875473Y-300907D01*
X877001Y-301199D01*
X878529Y-300616D01*
X880058Y-298866D01*
G01X890789Y-301199D02*
Y-289533D01*
G01Y-291866D02*
X891881Y-290699D01*
X892973Y-289824D01*
X894501Y-289533D01*
X895592Y-289824D01*
X896903Y-290699D01*
G01X959846Y-328699D02*
X962902Y-346199D01*
X966396Y-328699D01*
X969889Y-346199D01*
X972946Y-328699D01*
G01X979529Y-346199D02*
Y-328699D01*
X984769D01*
X986516Y-329574D01*
X987826Y-331616D01*
X988263Y-333949D01*
X987826Y-336282D01*
X986734Y-338032D01*
X984769Y-338908D01*
X979529D01*
G01X996811Y-346199D02*
Y-328699D01*
G01X1005981D02*
Y-346199D01*
G01Y-337449D02*
X996811D01*
G01X1016058Y-340366D02*
X1021734D01*
G01X1031593Y-346199D02*
Y-328699D01*
G01X1039889D02*
X1031593Y-339491D01*
G01X1041199Y-346199D02*
X1035304Y-334533D01*
G01X1058263Y-346199D02*
X1049529D01*
Y-328699D01*
X1058263D01*
G01X1054769Y-337157D02*
X1049529D01*
G01X1066374Y-346199D02*
Y-328699D01*
X1076418Y-346199D01*
Y-328699D01*
G01X1083874Y-346199D02*
Y-328699D01*
X1093918Y-346199D01*
Y-328699D01*
G01X961593Y-301199D02*
Y-283699D01*
X965959D01*
X967706Y-284574D01*
X969016Y-285741D01*
X970108Y-287490D01*
X970981Y-289533D01*
X971199Y-292449D01*
X970981Y-295366D01*
X970108Y-297408D01*
X969016Y-299158D01*
X967706Y-300324D01*
X965959Y-301199D01*
X961593D01*
G01X980621Y-293324D02*
X987608D01*
X986953Y-291282D01*
X985861Y-290116D01*
X984333Y-289533D01*
X982804Y-289824D01*
X981494Y-290699D01*
X980621Y-292741D01*
X980184Y-294491D01*
Y-296241D01*
X980621Y-297991D01*
X981713Y-299741D01*
X983023Y-300907D01*
X984551Y-301199D01*
X986079Y-300616D01*
X987608Y-298866D01*
G01X998121Y-299158D02*
X999213Y-300324D01*
X1000741Y-301199D01*
X1002051D01*
X1003361Y-300616D01*
X1004234Y-299741D01*
X1004671Y-298575D01*
X1004453Y-296824D01*
X1003579Y-295949D01*
X999649Y-294199D01*
X998776Y-292157D01*
X999213Y-290699D01*
X1000086Y-289824D01*
X1001396Y-289533D01*
X1002706Y-289824D01*
X1004016Y-290699D01*
G01X1018896Y-289533D02*
Y-301199D01*
G01Y-284866D02*
X1018459Y-284574D01*
Y-283991D01*
X1018896Y-283699D01*
X1019333Y-283991D01*
Y-284574D01*
X1018896Y-284866D01*
G01X1033339Y-305574D02*
X1034868Y-306741D01*
X1036614Y-307032D01*
X1038142Y-306741D01*
X1039453Y-305283D01*
X1040326Y-303241D01*
Y-289533D01*
G01Y-291866D02*
X1039453Y-290699D01*
X1038142Y-289824D01*
X1036614Y-289533D01*
X1034868Y-290116D01*
X1033776Y-291282D01*
X1032902Y-293324D01*
X1032466Y-295366D01*
X1032684Y-297116D01*
X1033558Y-299158D01*
X1034868Y-300616D01*
X1036614Y-301199D01*
X1037924Y-300907D01*
X1039453Y-299741D01*
X1040326Y-298575D01*
G01X1050184Y-301199D02*
Y-289533D01*
G01Y-292449D02*
X1051058Y-290991D01*
X1052368Y-289824D01*
X1054114Y-289533D01*
X1055642Y-289824D01*
X1056953Y-290991D01*
X1057608Y-293032D01*
Y-301199D01*
G01X1068121Y-293324D02*
X1075108D01*
X1074453Y-291282D01*
X1073361Y-290116D01*
X1071833Y-289533D01*
X1070304Y-289824D01*
X1068994Y-290699D01*
X1068121Y-292741D01*
X1067684Y-294491D01*
Y-296241D01*
X1068121Y-297991D01*
X1069213Y-299741D01*
X1070523Y-300907D01*
X1072051Y-301199D01*
X1073579Y-300616D01*
X1075108Y-298866D01*
G01X1085839Y-301199D02*
Y-289533D01*
G01Y-291866D02*
X1086931Y-290699D01*
X1088023Y-289824D01*
X1089551Y-289533D01*
X1090642Y-289824D01*
X1091953Y-290699D01*
G01X1132596Y-346199D02*
Y-328699D01*
X1129976Y-332199D01*
G01Y-346199D02*
X1135216D01*
G01X1150096D02*
Y-328699D01*
X1147476Y-332199D01*
G01Y-346199D02*
X1152716D01*
G01X1163666Y-346782D02*
X1171526Y-328699D01*
G01X1185096Y-346199D02*
Y-328699D01*
X1182476Y-332199D01*
G01Y-346199D02*
X1187716D01*
G01X1198448Y-338908D02*
X1199976Y-336866D01*
X1201286Y-335699D01*
X1203033Y-335116D01*
X1204561Y-335699D01*
X1205653Y-336866D01*
X1206526Y-338616D01*
X1206744Y-340657D01*
X1206526Y-342408D01*
X1205653Y-344158D01*
X1204342Y-345616D01*
X1202814Y-346199D01*
X1201068Y-345616D01*
X1199539Y-343866D01*
X1198666Y-341241D01*
X1198448Y-338324D01*
X1198884Y-334533D01*
X1199539Y-332490D01*
X1200631Y-330449D01*
X1202159Y-328991D01*
X1203688Y-328699D01*
X1205216Y-329282D01*
X1206308Y-330741D01*
G01X1216166Y-346782D02*
X1224026Y-328699D01*
G01X1233448Y-331616D02*
X1234758Y-329866D01*
X1236286Y-328991D01*
X1238033Y-328699D01*
X1240216Y-329282D01*
X1241744Y-330741D01*
X1242181Y-332490D01*
X1241963Y-334241D01*
X1241089Y-335699D01*
X1236723Y-338616D01*
X1234758Y-340657D01*
X1233448Y-343575D01*
X1233011Y-346199D01*
X1242181D01*
G01X1255096Y-328699D02*
X1253349Y-329282D01*
X1252039Y-330741D01*
X1251166Y-332490D01*
X1250511Y-334824D01*
X1250293Y-337449D01*
X1250511Y-340074D01*
X1251166Y-342408D01*
X1252039Y-344158D01*
X1253349Y-345616D01*
X1255096Y-346199D01*
X1256842Y-345616D01*
X1258153Y-344158D01*
X1259026Y-342408D01*
X1259681Y-340074D01*
X1259899Y-337449D01*
X1259681Y-334824D01*
X1259026Y-332490D01*
X1258153Y-330741D01*
X1256842Y-329282D01*
X1255096Y-328699D01*
G01X1272596Y-346199D02*
Y-328699D01*
X1269976Y-332199D01*
G01Y-346199D02*
X1275216D01*
G01X1285948Y-338908D02*
X1287476Y-336866D01*
X1288786Y-335699D01*
X1290533Y-335116D01*
X1292061Y-335699D01*
X1293153Y-336866D01*
X1294026Y-338616D01*
X1294244Y-340657D01*
X1294026Y-342408D01*
X1293153Y-344158D01*
X1291842Y-345616D01*
X1290314Y-346199D01*
X1288568Y-345616D01*
X1287039Y-343866D01*
X1286166Y-341241D01*
X1285948Y-338324D01*
X1286384Y-334533D01*
X1287039Y-332490D01*
X1288131Y-330449D01*
X1289659Y-328991D01*
X1291188Y-328699D01*
X1292716Y-329282D01*
X1293808Y-330741D01*
G01X1180293Y-301199D02*
Y-283699D01*
X1184659D01*
X1186406Y-284574D01*
X1187716Y-285741D01*
X1188808Y-287490D01*
X1189681Y-289533D01*
X1189899Y-292449D01*
X1189681Y-295366D01*
X1188808Y-297408D01*
X1187716Y-299158D01*
X1186406Y-300324D01*
X1184659Y-301199D01*
X1180293D01*
G01X1206526D02*
Y-289533D01*
G01Y-291574D02*
X1205653Y-290408D01*
X1204342Y-289824D01*
X1202814Y-289533D01*
X1201286Y-290116D01*
X1199976Y-291282D01*
X1199102Y-293032D01*
X1198666Y-295366D01*
X1199102Y-297699D01*
X1199976Y-299449D01*
X1201286Y-300616D01*
X1202814Y-301199D01*
X1204342Y-300907D01*
X1205653Y-300033D01*
X1206526Y-298866D01*
G01X1220096Y-283699D02*
Y-301199D01*
G01X1217039Y-289533D02*
X1223153D01*
G01X1234321Y-293324D02*
X1241308D01*
X1240653Y-291282D01*
X1239561Y-290116D01*
X1238033Y-289533D01*
X1236504Y-289824D01*
X1235194Y-290699D01*
X1234321Y-292741D01*
X1233884Y-294491D01*
Y-296241D01*
X1234321Y-297991D01*
X1235413Y-299741D01*
X1236723Y-300907D01*
X1238251Y-301199D01*
X1239779Y-300616D01*
X1241308Y-298866D01*
M02*
